FILE_TYPE = MACRO_DRAWING;
SET COLOR_WIRE YELLOW;
SET COLOR_PROP MONO;
SET COLOR_DOT WHITE;
SET COLOR_ARC YELLOW;
SET COLOR_BODY GREEN;
SET COLOR_NOTE MONO;
SET PROP_DISPLAY VALUE;
SET PAGE_NUMBER P32;
FORCEADD OFFPAGE..1
(-7275 3500);
FORCEPROP 2 LAST $XR0 186 
J 0
(-7557 3500);
DISPLAY 0.638298 (-7557 3500);
PAINT MONO (-7557 3500);
FORCEPROP 2 LAST $XR1 187 
J 0
(-7677 3500);
DISPLAY 0.638298 (-7677 3500);
PAINT MONO (-7677 3500);
FORCEPROP 2 LAST CDS_LIB mstr_standard
J 0
(-7275 3500);
PAINT MONO (-7275 3500);
DISPLAY INVISIBLE (-7275 3500);
FORCEPROP 1 LAST OFFPAGE TRUE
J 0
(-6950 3375);
DISPLAY 1.170213 (-6950 3375);
PAINT GREEN (-6950 3375);
DISPLAY INVISIBLE (-6950 3375);
FORCEPROP 1 LAST COMMENT_BODY TRUE
J 0
(-7150 3400);
DISPLAY 1.170213 (-7150 3400);
PAINT GREEN (-7150 3400);
DISPLAY INVISIBLE (-7150 3400);
FORCEPROP 2 LAST PATH I1
J 0
(-7225 3575);
DISPLAY 1.021277 (-7225 3575);
PAINT ORANGE (-7225 3575);
DISPLAY INVISIBLE (-7225 3575);
FORCEADD TAP..1
R 2
(-5875 2025);
FORCEPROP 3 LASTPIN (-5825 2025) SIG_NAME P3E_CPU0_PE3_OCP_RXP<3>
J 0
(-5815 2035);
DISPLAY 0.659574 (-5815 2035);
PAINT MONO (-5815 2035);
DISPLAY INVISIBLE (-5815 2035);
FORCEPROP 1 LASTPIN (-5825 2025) BN 3
J 2
(-5813 2033);
DISPLAY 0.617021 (-5813 2033);
PAINT PINK (-5813 2033);
FORCEPROP 2 LAST CDS_LIB mstr_standard
J 0
(-5875 2025);
PAINT MONO (-5875 2025);
DISPLAY INVISIBLE (-5875 2025);
FORCEPROP 1 LAST BODY_TYPE PLUMBING
J 2
(-5875 2075);
DISPLAY 1.446809 (-5875 2075);
PAINT GREEN (-5875 2075);
DISPLAY INVISIBLE (-5875 2075);
FORCEPROP 1 LAST HDL_TAP TRUE
J 2
(-6200 1900);
DISPLAY 1.446809 (-6200 1900);
PAINT GREEN (-6200 1900);
DISPLAY INVISIBLE (-6200 1900);
FORCEPROP 1 LAST PATH I15
J 2
(-5873 2025);
DISPLAY 0.872340 (-5873 2025);
PAINT GREEN (-5873 2025);
DISPLAY INVISIBLE (-5873 2025);
FORCEADD OFFPAGE..1
(-7275 3625);
FORCEPROP 2 LAST $XR0 186 
J 0
(-7557 3625);
DISPLAY 0.638298 (-7557 3625);
PAINT MONO (-7557 3625);
FORCEPROP 2 LAST $XR1 187 
J 0
(-7677 3625);
DISPLAY 0.638298 (-7677 3625);
PAINT MONO (-7677 3625);
FORCEPROP 2 LAST CDS_LIB mstr_standard
J 0
(-7275 3625);
PAINT MONO (-7275 3625);
DISPLAY INVISIBLE (-7275 3625);
FORCEPROP 1 LAST OFFPAGE TRUE
J 0
(-6950 3500);
DISPLAY 1.170213 (-6950 3500);
PAINT GREEN (-6950 3500);
DISPLAY INVISIBLE (-6950 3500);
FORCEPROP 1 LAST COMMENT_BODY TRUE
J 0
(-7150 3525);
DISPLAY 1.170213 (-7150 3525);
PAINT GREEN (-7150 3525);
DISPLAY INVISIBLE (-7150 3525);
FORCEPROP 2 LAST PATH I2
J 0
(-7225 3700);
DISPLAY 1.021277 (-7225 3700);
PAINT ORANGE (-7225 3700);
DISPLAY INVISIBLE (-7225 3700);
FORCEADD TAP..1
R 2
(-6025 2625);
FORCEPROP 3 LASTPIN (-5975 2625) SIG_NAME P3E_CPU0_PE3_OCP_RXN<8>
J 0
(-5965 2635);
DISPLAY 0.659574 (-5965 2635);
PAINT MONO (-5965 2635);
DISPLAY INVISIBLE (-5965 2635);
FORCEPROP 1 LASTPIN (-5975 2625) BN 8
J 2
(-5963 2633);
DISPLAY 0.617021 (-5963 2633);
PAINT PINK (-5963 2633);
FORCEPROP 2 LAST CDS_LIB mstr_standard
J 0
(-6025 2625);
PAINT MONO (-6025 2625);
DISPLAY INVISIBLE (-6025 2625);
FORCEPROP 1 LAST BODY_TYPE PLUMBING
J 2
(-6025 2675);
DISPLAY 1.446809 (-6025 2675);
PAINT GREEN (-6025 2675);
DISPLAY INVISIBLE (-6025 2675);
FORCEPROP 1 LAST HDL_TAP TRUE
J 2
(-6350 2500);
DISPLAY 1.446809 (-6350 2500);
PAINT GREEN (-6350 2500);
DISPLAY INVISIBLE (-6350 2500);
FORCEPROP 1 LAST PATH I20
J 2
(-6023 2625);
DISPLAY 0.872340 (-6023 2625);
PAINT GREEN (-6023 2625);
DISPLAY INVISIBLE (-6023 2625);
FORCEADD TAP..1
R 2
(-6025 2675);
FORCEPROP 3 LASTPIN (-5975 2675) SIG_NAME P3E_CPU0_PE3_OCP_RXN<9>
J 0
(-5965 2685);
DISPLAY 0.659574 (-5965 2685);
PAINT MONO (-5965 2685);
DISPLAY INVISIBLE (-5965 2685);
FORCEPROP 1 LASTPIN (-5975 2675) BN 9
J 2
(-5963 2683);
DISPLAY 0.617021 (-5963 2683);
PAINT PINK (-5963 2683);
FORCEPROP 2 LAST CDS_LIB mstr_standard
J 0
(-6025 2675);
PAINT MONO (-6025 2675);
DISPLAY INVISIBLE (-6025 2675);
FORCEPROP 1 LAST BODY_TYPE PLUMBING
J 2
(-6025 2725);
DISPLAY 1.446809 (-6025 2725);
PAINT GREEN (-6025 2725);
DISPLAY INVISIBLE (-6025 2725);
FORCEPROP 1 LAST HDL_TAP TRUE
J 2
(-6350 2550);
DISPLAY 1.446809 (-6350 2550);
PAINT GREEN (-6350 2550);
DISPLAY INVISIBLE (-6350 2550);
FORCEPROP 1 LAST PATH I21
J 2
(-6023 2675);
DISPLAY 0.872340 (-6023 2675);
PAINT GREEN (-6023 2675);
DISPLAY INVISIBLE (-6023 2675);
FORCEADD TAP..1
R 2
(-6025 2725);
FORCEPROP 3 LASTPIN (-5975 2725) SIG_NAME P3E_CPU0_PE3_OCP_RXN<10>
J 0
(-5965 2735);
DISPLAY 0.659574 (-5965 2735);
PAINT MONO (-5965 2735);
DISPLAY INVISIBLE (-5965 2735);
FORCEPROP 1 LASTPIN (-5975 2725) BN 10
J 2
(-5963 2733);
DISPLAY 0.617021 (-5963 2733);
PAINT PINK (-5963 2733);
FORCEPROP 2 LAST CDS_LIB mstr_standard
J 0
(-6025 2725);
PAINT MONO (-6025 2725);
DISPLAY INVISIBLE (-6025 2725);
FORCEPROP 1 LAST BODY_TYPE PLUMBING
J 2
(-6025 2775);
DISPLAY 1.446809 (-6025 2775);
PAINT GREEN (-6025 2775);
DISPLAY INVISIBLE (-6025 2775);
FORCEPROP 1 LAST HDL_TAP TRUE
J 2
(-6350 2600);
DISPLAY 1.446809 (-6350 2600);
PAINT GREEN (-6350 2600);
DISPLAY INVISIBLE (-6350 2600);
FORCEPROP 1 LAST PATH I22
J 2
(-6023 2725);
DISPLAY 0.872340 (-6023 2725);
PAINT GREEN (-6023 2725);
DISPLAY INVISIBLE (-6023 2725);
FORCEADD TAP..1
R 2
(-6025 2775);
FORCEPROP 3 LASTPIN (-5975 2775) SIG_NAME P3E_CPU0_PE3_OCP_RXN<11>
J 0
(-5965 2785);
DISPLAY 0.659574 (-5965 2785);
PAINT MONO (-5965 2785);
DISPLAY INVISIBLE (-5965 2785);
FORCEPROP 1 LASTPIN (-5975 2775) BN 11
J 2
(-5963 2783);
DISPLAY 0.617021 (-5963 2783);
PAINT PINK (-5963 2783);
FORCEPROP 2 LAST CDS_LIB mstr_standard
J 0
(-6025 2775);
PAINT MONO (-6025 2775);
DISPLAY INVISIBLE (-6025 2775);
FORCEPROP 1 LAST BODY_TYPE PLUMBING
J 2
(-6025 2825);
DISPLAY 1.446809 (-6025 2825);
PAINT GREEN (-6025 2825);
DISPLAY INVISIBLE (-6025 2825);
FORCEPROP 1 LAST HDL_TAP TRUE
J 2
(-6350 2650);
DISPLAY 1.446809 (-6350 2650);
PAINT GREEN (-6350 2650);
DISPLAY INVISIBLE (-6350 2650);
FORCEPROP 1 LAST PATH I23
J 2
(-6023 2775);
DISPLAY 0.872340 (-6023 2775);
PAINT GREEN (-6023 2775);
DISPLAY INVISIBLE (-6023 2775);
FORCEADD TAP..1
R 2
(-5875 2875);
FORCEPROP 3 LASTPIN (-5825 2875) SIG_NAME P3E_CPU0_PE3_OCP_RXP<8>
J 0
(-5815 2885);
DISPLAY 0.659574 (-5815 2885);
PAINT MONO (-5815 2885);
DISPLAY INVISIBLE (-5815 2885);
FORCEPROP 1 LASTPIN (-5825 2875) BN 8
J 2
(-5813 2883);
DISPLAY 0.617021 (-5813 2883);
PAINT PINK (-5813 2883);
FORCEPROP 2 LAST CDS_LIB mstr_standard
J 0
(-5875 2875);
PAINT MONO (-5875 2875);
DISPLAY INVISIBLE (-5875 2875);
FORCEPROP 1 LAST BODY_TYPE PLUMBING
J 2
(-5875 2925);
DISPLAY 1.446809 (-5875 2925);
PAINT GREEN (-5875 2925);
DISPLAY INVISIBLE (-5875 2925);
FORCEPROP 1 LAST HDL_TAP TRUE
J 2
(-6200 2750);
DISPLAY 1.446809 (-6200 2750);
PAINT GREEN (-6200 2750);
DISPLAY INVISIBLE (-6200 2750);
FORCEPROP 1 LAST PATH I24
J 2
(-5873 2875);
DISPLAY 0.872340 (-5873 2875);
PAINT GREEN (-5873 2875);
DISPLAY INVISIBLE (-5873 2875);
FORCEADD TAP..1
R 2
(-5875 2975);
FORCEPROP 3 LASTPIN (-5825 2975) SIG_NAME P3E_CPU0_PE3_OCP_RXP<10>
J 0
(-5815 2985);
DISPLAY 0.659574 (-5815 2985);
PAINT MONO (-5815 2985);
DISPLAY INVISIBLE (-5815 2985);
FORCEPROP 1 LASTPIN (-5825 2975) BN 10
J 2
(-5813 2983);
DISPLAY 0.617021 (-5813 2983);
PAINT PINK (-5813 2983);
FORCEPROP 2 LAST CDS_LIB mstr_standard
J 0
(-5875 2975);
PAINT MONO (-5875 2975);
DISPLAY INVISIBLE (-5875 2975);
FORCEPROP 1 LAST BODY_TYPE PLUMBING
J 2
(-5875 3025);
DISPLAY 1.446809 (-5875 3025);
PAINT GREEN (-5875 3025);
DISPLAY INVISIBLE (-5875 3025);
FORCEPROP 1 LAST HDL_TAP TRUE
J 2
(-6200 2850);
DISPLAY 1.446809 (-6200 2850);
PAINT GREEN (-6200 2850);
DISPLAY INVISIBLE (-6200 2850);
FORCEPROP 1 LAST PATH I25
J 2
(-5873 2975);
DISPLAY 0.872340 (-5873 2975);
PAINT GREEN (-5873 2975);
DISPLAY INVISIBLE (-5873 2975);
FORCEADD TAP..1
R 2
(-5875 2925);
FORCEPROP 3 LASTPIN (-5825 2925) SIG_NAME P3E_CPU0_PE3_OCP_RXP<9>
J 0
(-5815 2935);
DISPLAY 0.659574 (-5815 2935);
PAINT MONO (-5815 2935);
DISPLAY INVISIBLE (-5815 2935);
FORCEPROP 1 LASTPIN (-5825 2925) BN 9
J 2
(-5813 2933);
DISPLAY 0.617021 (-5813 2933);
PAINT PINK (-5813 2933);
FORCEPROP 2 LAST CDS_LIB mstr_standard
J 0
(-5875 2925);
PAINT MONO (-5875 2925);
DISPLAY INVISIBLE (-5875 2925);
FORCEPROP 1 LAST BODY_TYPE PLUMBING
J 2
(-5875 2975);
DISPLAY 1.446809 (-5875 2975);
PAINT GREEN (-5875 2975);
DISPLAY INVISIBLE (-5875 2975);
FORCEPROP 1 LAST HDL_TAP TRUE
J 2
(-6200 2800);
DISPLAY 1.446809 (-6200 2800);
PAINT GREEN (-6200 2800);
DISPLAY INVISIBLE (-6200 2800);
FORCEPROP 1 LAST PATH I26
J 2
(-5873 2925);
DISPLAY 0.872340 (-5873 2925);
PAINT GREEN (-5873 2925);
DISPLAY INVISIBLE (-5873 2925);
FORCEADD TAP..1
R 2
(-5875 3025);
FORCEPROP 3 LASTPIN (-5825 3025) SIG_NAME P3E_CPU0_PE3_OCP_RXP<11>
J 0
(-5815 3035);
DISPLAY 0.659574 (-5815 3035);
PAINT MONO (-5815 3035);
DISPLAY INVISIBLE (-5815 3035);
FORCEPROP 1 LASTPIN (-5825 3025) BN 11
J 2
(-5813 3033);
DISPLAY 0.617021 (-5813 3033);
PAINT PINK (-5813 3033);
FORCEPROP 2 LAST CDS_LIB mstr_standard
J 0
(-5875 3025);
PAINT MONO (-5875 3025);
DISPLAY INVISIBLE (-5875 3025);
FORCEPROP 1 LAST BODY_TYPE PLUMBING
J 2
(-5875 3075);
DISPLAY 1.446809 (-5875 3075);
PAINT GREEN (-5875 3075);
DISPLAY INVISIBLE (-5875 3075);
FORCEPROP 1 LAST HDL_TAP TRUE
J 2
(-6200 2900);
DISPLAY 1.446809 (-6200 2900);
PAINT GREEN (-6200 2900);
DISPLAY INVISIBLE (-6200 2900);
FORCEPROP 1 LAST PATH I27
J 2
(-5873 3025);
DISPLAY 0.872340 (-5873 3025);
PAINT GREEN (-5873 3025);
DISPLAY INVISIBLE (-5873 3025);
FORCEADD TAP..1
R 2
(-6025 3125);
FORCEPROP 3 LASTPIN (-5975 3125) SIG_NAME P3E_CPU0_PE3_OCP_RXN<12>
J 0
(-5965 3135);
DISPLAY 0.659574 (-5965 3135);
PAINT MONO (-5965 3135);
DISPLAY INVISIBLE (-5965 3135);
FORCEPROP 1 LASTPIN (-5975 3125) BN 12
J 2
(-5963 3133);
DISPLAY 0.617021 (-5963 3133);
PAINT PINK (-5963 3133);
FORCEPROP 2 LAST CDS_LIB mstr_standard
J 0
(-6025 3125);
PAINT MONO (-6025 3125);
DISPLAY INVISIBLE (-6025 3125);
FORCEPROP 1 LAST BODY_TYPE PLUMBING
J 2
(-6025 3175);
DISPLAY 1.446809 (-6025 3175);
PAINT GREEN (-6025 3175);
DISPLAY INVISIBLE (-6025 3175);
FORCEPROP 1 LAST HDL_TAP TRUE
J 2
(-6350 3000);
DISPLAY 1.446809 (-6350 3000);
PAINT GREEN (-6350 3000);
DISPLAY INVISIBLE (-6350 3000);
FORCEPROP 1 LAST PATH I28
J 2
(-6023 3125);
DISPLAY 0.872340 (-6023 3125);
PAINT GREEN (-6023 3125);
DISPLAY INVISIBLE (-6023 3125);
FORCEADD TAP..1
R 2
(-6025 3175);
FORCEPROP 3 LASTPIN (-5975 3175) SIG_NAME P3E_CPU0_PE3_OCP_RXN<13>
J 0
(-5965 3185);
DISPLAY 0.659574 (-5965 3185);
PAINT MONO (-5965 3185);
DISPLAY INVISIBLE (-5965 3185);
FORCEPROP 1 LASTPIN (-5975 3175) BN 13
J 2
(-5963 3183);
DISPLAY 0.617021 (-5963 3183);
PAINT PINK (-5963 3183);
FORCEPROP 2 LAST CDS_LIB mstr_standard
J 0
(-6025 3175);
PAINT MONO (-6025 3175);
DISPLAY INVISIBLE (-6025 3175);
FORCEPROP 1 LAST BODY_TYPE PLUMBING
J 2
(-6025 3225);
DISPLAY 1.446809 (-6025 3225);
PAINT GREEN (-6025 3225);
DISPLAY INVISIBLE (-6025 3225);
FORCEPROP 1 LAST HDL_TAP TRUE
J 2
(-6350 3050);
DISPLAY 1.446809 (-6350 3050);
PAINT GREEN (-6350 3050);
DISPLAY INVISIBLE (-6350 3050);
FORCEPROP 1 LAST PATH I29
J 2
(-6023 3175);
DISPLAY 0.872340 (-6023 3175);
PAINT GREEN (-6023 3175);
DISPLAY INVISIBLE (-6023 3175);
FORCEADD TAP..1
R 2
(-6025 1625);
FORCEPROP 3 LASTPIN (-5975 1625) SIG_NAME P3E_CPU0_PE3_OCP_RXN<0>
J 0
(-5965 1635);
DISPLAY 0.659574 (-5965 1635);
PAINT MONO (-5965 1635);
DISPLAY INVISIBLE (-5965 1635);
FORCEPROP 1 LASTPIN (-5975 1625) BN 0
J 2
(-5963 1633);
DISPLAY 0.617021 (-5963 1633);
PAINT PINK (-5963 1633);
FORCEPROP 2 LAST CDS_LIB mstr_standard
J 0
(-6025 1625);
PAINT MONO (-6025 1625);
DISPLAY INVISIBLE (-6025 1625);
FORCEPROP 1 LAST BODY_TYPE PLUMBING
J 2
(-6025 1675);
DISPLAY 1.446809 (-6025 1675);
PAINT GREEN (-6025 1675);
DISPLAY INVISIBLE (-6025 1675);
FORCEPROP 1 LAST HDL_TAP TRUE
J 2
(-6350 1500);
DISPLAY 1.446809 (-6350 1500);
PAINT GREEN (-6350 1500);
DISPLAY INVISIBLE (-6350 1500);
FORCEPROP 1 LAST PATH I3
J 2
(-6023 1625);
DISPLAY 0.872340 (-6023 1625);
PAINT GREEN (-6023 1625);
DISPLAY INVISIBLE (-6023 1625);
FORCEADD TAP..1
R 2
(-6025 3275);
FORCEPROP 3 LASTPIN (-5975 3275) SIG_NAME P3E_CPU0_PE3_OCP_RXN<15>
J 0
(-5965 3285);
DISPLAY 0.659574 (-5965 3285);
PAINT MONO (-5965 3285);
DISPLAY INVISIBLE (-5965 3285);
FORCEPROP 1 LASTPIN (-5975 3275) BN 15
J 2
(-5963 3283);
DISPLAY 0.617021 (-5963 3283);
PAINT PINK (-5963 3283);
FORCEPROP 2 LAST CDS_LIB mstr_standard
J 0
(-6025 3275);
PAINT MONO (-6025 3275);
DISPLAY INVISIBLE (-6025 3275);
FORCEPROP 1 LAST BODY_TYPE PLUMBING
J 2
(-6025 3325);
DISPLAY 1.446809 (-6025 3325);
PAINT GREEN (-6025 3325);
DISPLAY INVISIBLE (-6025 3325);
FORCEPROP 1 LAST HDL_TAP TRUE
J 2
(-6350 3150);
DISPLAY 1.446809 (-6350 3150);
PAINT GREEN (-6350 3150);
DISPLAY INVISIBLE (-6350 3150);
FORCEPROP 1 LAST PATH I30
J 2
(-6023 3275);
DISPLAY 0.872340 (-6023 3275);
PAINT GREEN (-6023 3275);
DISPLAY INVISIBLE (-6023 3275);
FORCEADD TAP..1
R 2
(-6025 3225);
FORCEPROP 3 LASTPIN (-5975 3225) SIG_NAME P3E_CPU0_PE3_OCP_RXN<14>
J 0
(-5965 3235);
DISPLAY 0.659574 (-5965 3235);
PAINT MONO (-5965 3235);
DISPLAY INVISIBLE (-5965 3235);
FORCEPROP 1 LASTPIN (-5975 3225) BN 14
J 2
(-5963 3233);
DISPLAY 0.617021 (-5963 3233);
PAINT PINK (-5963 3233);
FORCEPROP 2 LAST CDS_LIB mstr_standard
J 0
(-6025 3225);
PAINT MONO (-6025 3225);
DISPLAY INVISIBLE (-6025 3225);
FORCEPROP 1 LAST BODY_TYPE PLUMBING
J 2
(-6025 3275);
DISPLAY 1.446809 (-6025 3275);
PAINT GREEN (-6025 3275);
DISPLAY INVISIBLE (-6025 3275);
FORCEPROP 1 LAST HDL_TAP TRUE
J 2
(-6350 3100);
DISPLAY 1.446809 (-6350 3100);
PAINT GREEN (-6350 3100);
DISPLAY INVISIBLE (-6350 3100);
FORCEPROP 1 LAST PATH I31
J 2
(-6023 3225);
DISPLAY 0.872340 (-6023 3225);
PAINT GREEN (-6023 3225);
DISPLAY INVISIBLE (-6023 3225);
FORCEADD TAP..1
R 2
(-5875 3375);
FORCEPROP 3 LASTPIN (-5825 3375) SIG_NAME P3E_CPU0_PE3_OCP_RXP<12>
J 0
(-5815 3385);
DISPLAY 0.659574 (-5815 3385);
PAINT MONO (-5815 3385);
DISPLAY INVISIBLE (-5815 3385);
FORCEPROP 1 LASTPIN (-5825 3375) BN 12
J 2
(-5813 3383);
DISPLAY 0.617021 (-5813 3383);
PAINT PINK (-5813 3383);
FORCEPROP 2 LAST CDS_LIB mstr_standard
J 0
(-5875 3375);
PAINT MONO (-5875 3375);
DISPLAY INVISIBLE (-5875 3375);
FORCEPROP 1 LAST BODY_TYPE PLUMBING
J 2
(-5875 3425);
DISPLAY 1.446809 (-5875 3425);
PAINT GREEN (-5875 3425);
DISPLAY INVISIBLE (-5875 3425);
FORCEPROP 1 LAST HDL_TAP TRUE
J 2
(-6200 3250);
DISPLAY 1.446809 (-6200 3250);
PAINT GREEN (-6200 3250);
DISPLAY INVISIBLE (-6200 3250);
FORCEPROP 1 LAST PATH I32
J 2
(-5873 3375);
DISPLAY 0.872340 (-5873 3375);
PAINT GREEN (-5873 3375);
DISPLAY INVISIBLE (-5873 3375);
FORCEADD TAP..1
R 2
(-5875 3425);
FORCEPROP 3 LASTPIN (-5825 3425) SIG_NAME P3E_CPU0_PE3_OCP_RXP<13>
J 0
(-5815 3435);
DISPLAY 0.659574 (-5815 3435);
PAINT MONO (-5815 3435);
DISPLAY INVISIBLE (-5815 3435);
FORCEPROP 1 LASTPIN (-5825 3425) BN 13
J 2
(-5813 3433);
DISPLAY 0.617021 (-5813 3433);
PAINT PINK (-5813 3433);
FORCEPROP 2 LAST CDS_LIB mstr_standard
J 0
(-5875 3425);
PAINT MONO (-5875 3425);
DISPLAY INVISIBLE (-5875 3425);
FORCEPROP 1 LAST BODY_TYPE PLUMBING
J 2
(-5875 3475);
DISPLAY 1.446809 (-5875 3475);
PAINT GREEN (-5875 3475);
DISPLAY INVISIBLE (-5875 3475);
FORCEPROP 1 LAST HDL_TAP TRUE
J 2
(-6200 3300);
DISPLAY 1.446809 (-6200 3300);
PAINT GREEN (-6200 3300);
DISPLAY INVISIBLE (-6200 3300);
FORCEPROP 1 LAST PATH I33
J 2
(-5873 3425);
DISPLAY 0.872340 (-5873 3425);
PAINT GREEN (-5873 3425);
DISPLAY INVISIBLE (-5873 3425);
FORCEADD TAP..1
R 2
(-5875 3475);
FORCEPROP 3 LASTPIN (-5825 3475) SIG_NAME P3E_CPU0_PE3_OCP_RXP<14>
J 0
(-5815 3485);
DISPLAY 0.659574 (-5815 3485);
PAINT MONO (-5815 3485);
DISPLAY INVISIBLE (-5815 3485);
FORCEPROP 1 LASTPIN (-5825 3475) BN 14
J 2
(-5813 3483);
DISPLAY 0.617021 (-5813 3483);
PAINT PINK (-5813 3483);
FORCEPROP 2 LAST CDS_LIB mstr_standard
J 0
(-5875 3475);
PAINT MONO (-5875 3475);
DISPLAY INVISIBLE (-5875 3475);
FORCEPROP 1 LAST BODY_TYPE PLUMBING
J 2
(-5875 3525);
DISPLAY 1.446809 (-5875 3525);
PAINT GREEN (-5875 3525);
DISPLAY INVISIBLE (-5875 3525);
FORCEPROP 1 LAST HDL_TAP TRUE
J 2
(-6200 3350);
DISPLAY 1.446809 (-6200 3350);
PAINT GREEN (-6200 3350);
DISPLAY INVISIBLE (-6200 3350);
FORCEPROP 1 LAST PATH I34
J 2
(-5873 3475);
DISPLAY 0.872340 (-5873 3475);
PAINT GREEN (-5873 3475);
DISPLAY INVISIBLE (-5873 3475);
FORCEADD TAP..1
R 2
(-5875 3525);
FORCEPROP 3 LASTPIN (-5825 3525) SIG_NAME P3E_CPU0_PE3_OCP_RXP<15>
J 0
(-5815 3535);
DISPLAY 0.659574 (-5815 3535);
PAINT MONO (-5815 3535);
DISPLAY INVISIBLE (-5815 3535);
FORCEPROP 1 LASTPIN (-5825 3525) BN 15
J 2
(-5813 3533);
DISPLAY 0.617021 (-5813 3533);
PAINT PINK (-5813 3533);
FORCEPROP 2 LAST CDS_LIB mstr_standard
J 0
(-5875 3525);
PAINT MONO (-5875 3525);
DISPLAY INVISIBLE (-5875 3525);
FORCEPROP 1 LAST BODY_TYPE PLUMBING
J 2
(-5875 3575);
DISPLAY 1.446809 (-5875 3575);
PAINT GREEN (-5875 3575);
DISPLAY INVISIBLE (-5875 3575);
FORCEPROP 1 LAST HDL_TAP TRUE
J 2
(-6200 3400);
DISPLAY 1.446809 (-6200 3400);
PAINT GREEN (-6200 3400);
DISPLAY INVISIBLE (-6200 3400);
FORCEPROP 1 LAST PATH I35
J 2
(-5873 3525);
DISPLAY 0.872340 (-5873 3525);
PAINT GREEN (-5873 3525);
DISPLAY INVISIBLE (-5873 3525);
FORCEADD TAP..1
(-3000 1875);
FORCEPROP 3 LASTPIN (-3050 1875) SIG_NAME P3E_CPU0_PE3_OCP_TXP<0>
J 0
(-3040 1885);
DISPLAY 0.659574 (-3040 1885);
PAINT MONO (-3040 1885);
DISPLAY INVISIBLE (-3040 1885);
FORCEPROP 1 LASTPIN (-3050 1875) BN 0
J 0
(-3062 1883);
DISPLAY 0.617021 (-3062 1883);
PAINT PINK (-3062 1883);
FORCEPROP 2 LAST CDS_LIB mstr_standard
J 2
(-3000 1875);
PAINT MONO (-3000 1875);
DISPLAY INVISIBLE (-3000 1875);
FORCEPROP 1 LAST BODY_TYPE PLUMBING
J 0
(-3000 1925);
DISPLAY 1.446809 (-3000 1925);
PAINT GREEN (-3000 1925);
DISPLAY INVISIBLE (-3000 1925);
FORCEPROP 1 LAST HDL_TAP TRUE
J 0
(-2675 1750);
DISPLAY 1.446809 (-2675 1750);
PAINT GREEN (-2675 1750);
DISPLAY INVISIBLE (-2675 1750);
FORCEPROP 1 LAST PATH I36
J 0
(-3002 1875);
DISPLAY 0.872340 (-3002 1875);
PAINT GREEN (-3002 1875);
DISPLAY INVISIBLE (-3002 1875);
FORCEADD TAP..1
(-3000 1975);
FORCEPROP 3 LASTPIN (-3050 1975) SIG_NAME P3E_CPU0_PE3_OCP_TXP<2>
J 0
(-3040 1985);
DISPLAY 0.659574 (-3040 1985);
PAINT MONO (-3040 1985);
DISPLAY INVISIBLE (-3040 1985);
FORCEPROP 1 LASTPIN (-3050 1975) BN 2
J 0
(-3062 1983);
DISPLAY 0.617021 (-3062 1983);
PAINT PINK (-3062 1983);
FORCEPROP 2 LAST CDS_LIB mstr_standard
J 2
(-3000 1975);
PAINT MONO (-3000 1975);
DISPLAY INVISIBLE (-3000 1975);
FORCEPROP 1 LAST BODY_TYPE PLUMBING
J 0
(-3000 2025);
DISPLAY 1.446809 (-3000 2025);
PAINT GREEN (-3000 2025);
DISPLAY INVISIBLE (-3000 2025);
FORCEPROP 1 LAST HDL_TAP TRUE
J 0
(-2675 1850);
DISPLAY 1.446809 (-2675 1850);
PAINT GREEN (-2675 1850);
DISPLAY INVISIBLE (-2675 1850);
FORCEPROP 1 LAST PATH I37
J 0
(-3002 1975);
DISPLAY 0.872340 (-3002 1975);
PAINT GREEN (-3002 1975);
DISPLAY INVISIBLE (-3002 1975);
FORCEADD TAP..1
(-3000 1925);
FORCEPROP 3 LASTPIN (-3050 1925) SIG_NAME P3E_CPU0_PE3_OCP_TXP<1>
J 0
(-3040 1935);
DISPLAY 0.659574 (-3040 1935);
PAINT MONO (-3040 1935);
DISPLAY INVISIBLE (-3040 1935);
FORCEPROP 1 LASTPIN (-3050 1925) BN 1
J 0
(-3062 1933);
DISPLAY 0.617021 (-3062 1933);
PAINT PINK (-3062 1933);
FORCEPROP 2 LAST CDS_LIB mstr_standard
J 2
(-3000 1925);
PAINT MONO (-3000 1925);
DISPLAY INVISIBLE (-3000 1925);
FORCEPROP 1 LAST BODY_TYPE PLUMBING
J 0
(-3000 1975);
DISPLAY 1.446809 (-3000 1975);
PAINT GREEN (-3000 1975);
DISPLAY INVISIBLE (-3000 1975);
FORCEPROP 1 LAST HDL_TAP TRUE
J 0
(-2675 1800);
DISPLAY 1.446809 (-2675 1800);
PAINT GREEN (-2675 1800);
DISPLAY INVISIBLE (-2675 1800);
FORCEPROP 1 LAST PATH I38
J 0
(-3002 1925);
DISPLAY 0.872340 (-3002 1925);
PAINT GREEN (-3002 1925);
DISPLAY INVISIBLE (-3002 1925);
FORCEADD TAP..1
(-2850 1625);
FORCEPROP 3 LASTPIN (-2900 1625) SIG_NAME P3E_CPU0_PE3_OCP_TXN<0>
J 0
(-2890 1635);
DISPLAY 0.659574 (-2890 1635);
PAINT MONO (-2890 1635);
DISPLAY INVISIBLE (-2890 1635);
FORCEPROP 1 LASTPIN (-2900 1625) BN 0
J 0
(-2912 1633);
DISPLAY 0.617021 (-2912 1633);
PAINT PINK (-2912 1633);
FORCEPROP 2 LAST CDS_LIB mstr_standard
J 2
(-2850 1625);
PAINT MONO (-2850 1625);
DISPLAY INVISIBLE (-2850 1625);
FORCEPROP 1 LAST BODY_TYPE PLUMBING
J 0
(-2850 1675);
DISPLAY 1.446809 (-2850 1675);
PAINT GREEN (-2850 1675);
DISPLAY INVISIBLE (-2850 1675);
FORCEPROP 1 LAST HDL_TAP TRUE
J 0
(-2525 1500);
DISPLAY 1.446809 (-2525 1500);
PAINT GREEN (-2525 1500);
DISPLAY INVISIBLE (-2525 1500);
FORCEPROP 1 LAST PATH I39
J 0
(-2852 1625);
DISPLAY 0.872340 (-2852 1625);
PAINT GREEN (-2852 1625);
DISPLAY INVISIBLE (-2852 1625);
FORCEADD TAP..1
R 2
(-6025 1675);
FORCEPROP 3 LASTPIN (-5975 1675) SIG_NAME P3E_CPU0_PE3_OCP_RXN<1>
J 0
(-5965 1685);
DISPLAY 0.659574 (-5965 1685);
PAINT MONO (-5965 1685);
DISPLAY INVISIBLE (-5965 1685);
FORCEPROP 1 LASTPIN (-5975 1675) BN 1
J 2
(-5963 1683);
DISPLAY 0.617021 (-5963 1683);
PAINT PINK (-5963 1683);
FORCEPROP 2 LAST CDS_LIB mstr_standard
J 0
(-6025 1675);
PAINT MONO (-6025 1675);
DISPLAY INVISIBLE (-6025 1675);
FORCEPROP 1 LAST BODY_TYPE PLUMBING
J 2
(-6025 1725);
DISPLAY 1.446809 (-6025 1725);
PAINT GREEN (-6025 1725);
DISPLAY INVISIBLE (-6025 1725);
FORCEPROP 1 LAST HDL_TAP TRUE
J 2
(-6350 1550);
DISPLAY 1.446809 (-6350 1550);
PAINT GREEN (-6350 1550);
DISPLAY INVISIBLE (-6350 1550);
FORCEPROP 1 LAST PATH I4
J 2
(-6023 1675);
DISPLAY 0.872340 (-6023 1675);
PAINT GREEN (-6023 1675);
DISPLAY INVISIBLE (-6023 1675);
FORCEADD TAP..1
(-2850 1675);
FORCEPROP 3 LASTPIN (-2900 1675) SIG_NAME P3E_CPU0_PE3_OCP_TXN<1>
J 0
(-2890 1685);
DISPLAY 0.659574 (-2890 1685);
PAINT MONO (-2890 1685);
DISPLAY INVISIBLE (-2890 1685);
FORCEPROP 1 LASTPIN (-2900 1675) BN 1
J 0
(-2912 1683);
DISPLAY 0.617021 (-2912 1683);
PAINT PINK (-2912 1683);
FORCEPROP 2 LAST CDS_LIB mstr_standard
J 2
(-2850 1675);
PAINT MONO (-2850 1675);
DISPLAY INVISIBLE (-2850 1675);
FORCEPROP 1 LAST BODY_TYPE PLUMBING
J 0
(-2850 1725);
DISPLAY 1.446809 (-2850 1725);
PAINT GREEN (-2850 1725);
DISPLAY INVISIBLE (-2850 1725);
FORCEPROP 1 LAST HDL_TAP TRUE
J 0
(-2525 1550);
DISPLAY 1.446809 (-2525 1550);
PAINT GREEN (-2525 1550);
DISPLAY INVISIBLE (-2525 1550);
FORCEPROP 1 LAST PATH I40
J 0
(-2852 1675);
DISPLAY 0.872340 (-2852 1675);
PAINT GREEN (-2852 1675);
DISPLAY INVISIBLE (-2852 1675);
FORCEADD TAP..1
(-2850 1725);
FORCEPROP 3 LASTPIN (-2900 1725) SIG_NAME P3E_CPU0_PE3_OCP_TXN<2>
J 0
(-2890 1735);
DISPLAY 0.659574 (-2890 1735);
PAINT MONO (-2890 1735);
DISPLAY INVISIBLE (-2890 1735);
FORCEPROP 1 LASTPIN (-2900 1725) BN 2
J 0
(-2912 1733);
DISPLAY 0.617021 (-2912 1733);
PAINT PINK (-2912 1733);
FORCEPROP 2 LAST CDS_LIB mstr_standard
J 2
(-2850 1725);
PAINT MONO (-2850 1725);
DISPLAY INVISIBLE (-2850 1725);
FORCEPROP 1 LAST BODY_TYPE PLUMBING
J 0
(-2850 1775);
DISPLAY 1.446809 (-2850 1775);
PAINT GREEN (-2850 1775);
DISPLAY INVISIBLE (-2850 1775);
FORCEPROP 1 LAST HDL_TAP TRUE
J 0
(-2525 1600);
DISPLAY 1.446809 (-2525 1600);
PAINT GREEN (-2525 1600);
DISPLAY INVISIBLE (-2525 1600);
FORCEPROP 1 LAST PATH I41
J 0
(-2852 1725);
DISPLAY 0.872340 (-2852 1725);
PAINT GREEN (-2852 1725);
DISPLAY INVISIBLE (-2852 1725);
FORCEADD TAP..1
(-2850 1775);
FORCEPROP 3 LASTPIN (-2900 1775) SIG_NAME P3E_CPU0_PE3_OCP_TXN<3>
J 0
(-2890 1785);
DISPLAY 0.659574 (-2890 1785);
PAINT MONO (-2890 1785);
DISPLAY INVISIBLE (-2890 1785);
FORCEPROP 1 LASTPIN (-2900 1775) BN 3
J 0
(-2912 1783);
DISPLAY 0.617021 (-2912 1783);
PAINT PINK (-2912 1783);
FORCEPROP 2 LAST CDS_LIB mstr_standard
J 2
(-2850 1775);
PAINT MONO (-2850 1775);
DISPLAY INVISIBLE (-2850 1775);
FORCEPROP 1 LAST BODY_TYPE PLUMBING
J 0
(-2850 1825);
DISPLAY 1.446809 (-2850 1825);
PAINT GREEN (-2850 1825);
DISPLAY INVISIBLE (-2850 1825);
FORCEPROP 1 LAST HDL_TAP TRUE
J 0
(-2525 1650);
DISPLAY 1.446809 (-2525 1650);
PAINT GREEN (-2525 1650);
DISPLAY INVISIBLE (-2525 1650);
FORCEPROP 1 LAST PATH I42
J 0
(-2852 1775);
DISPLAY 0.872340 (-2852 1775);
PAINT GREEN (-2852 1775);
DISPLAY INVISIBLE (-2852 1775);
FORCEADD TAP..1
(-3000 2475);
FORCEPROP 3 LASTPIN (-3050 2475) SIG_NAME P3E_CPU0_PE3_OCP_TXP<6>
J 0
(-3040 2485);
DISPLAY 0.659574 (-3040 2485);
PAINT MONO (-3040 2485);
DISPLAY INVISIBLE (-3040 2485);
FORCEPROP 1 LASTPIN (-3050 2475) BN 6
J 0
(-3062 2483);
DISPLAY 0.617021 (-3062 2483);
PAINT PINK (-3062 2483);
FORCEPROP 2 LAST CDS_LIB mstr_standard
J 2
(-3000 2475);
PAINT MONO (-3000 2475);
DISPLAY INVISIBLE (-3000 2475);
FORCEPROP 1 LAST BODY_TYPE PLUMBING
J 0
(-3000 2525);
DISPLAY 1.446809 (-3000 2525);
PAINT GREEN (-3000 2525);
DISPLAY INVISIBLE (-3000 2525);
FORCEPROP 1 LAST HDL_TAP TRUE
J 0
(-2675 2350);
DISPLAY 1.446809 (-2675 2350);
PAINT GREEN (-2675 2350);
DISPLAY INVISIBLE (-2675 2350);
FORCEPROP 1 LAST PATH I43
J 0
(-3002 2475);
DISPLAY 0.872340 (-3002 2475);
PAINT GREEN (-3002 2475);
DISPLAY INVISIBLE (-3002 2475);
FORCEADD TAP..1
(-3000 2525);
FORCEPROP 3 LASTPIN (-3050 2525) SIG_NAME P3E_CPU0_PE3_OCP_TXP<7>
J 0
(-3040 2535);
DISPLAY 0.659574 (-3040 2535);
PAINT MONO (-3040 2535);
DISPLAY INVISIBLE (-3040 2535);
FORCEPROP 1 LASTPIN (-3050 2525) BN 7
J 0
(-3062 2533);
DISPLAY 0.617021 (-3062 2533);
PAINT PINK (-3062 2533);
FORCEPROP 2 LAST CDS_LIB mstr_standard
J 2
(-3000 2525);
PAINT MONO (-3000 2525);
DISPLAY INVISIBLE (-3000 2525);
FORCEPROP 1 LAST BODY_TYPE PLUMBING
J 0
(-3000 2575);
DISPLAY 1.446809 (-3000 2575);
PAINT GREEN (-3000 2575);
DISPLAY INVISIBLE (-3000 2575);
FORCEPROP 1 LAST HDL_TAP TRUE
J 0
(-2675 2400);
DISPLAY 1.446809 (-2675 2400);
PAINT GREEN (-2675 2400);
DISPLAY INVISIBLE (-2675 2400);
FORCEPROP 1 LAST PATH I44
J 0
(-3002 2525);
DISPLAY 0.872340 (-3002 2525);
PAINT GREEN (-3002 2525);
DISPLAY INVISIBLE (-3002 2525);
FORCEADD TAP..1
(-3000 2425);
FORCEPROP 3 LASTPIN (-3050 2425) SIG_NAME P3E_CPU0_PE3_OCP_TXP<5>
J 0
(-3040 2435);
DISPLAY 0.659574 (-3040 2435);
PAINT MONO (-3040 2435);
DISPLAY INVISIBLE (-3040 2435);
FORCEPROP 1 LASTPIN (-3050 2425) BN 5
J 0
(-3062 2433);
DISPLAY 0.617021 (-3062 2433);
PAINT PINK (-3062 2433);
FORCEPROP 2 LAST CDS_LIB mstr_standard
J 2
(-3000 2425);
PAINT MONO (-3000 2425);
DISPLAY INVISIBLE (-3000 2425);
FORCEPROP 1 LAST BODY_TYPE PLUMBING
J 0
(-3000 2475);
DISPLAY 1.446809 (-3000 2475);
PAINT GREEN (-3000 2475);
DISPLAY INVISIBLE (-3000 2475);
FORCEPROP 1 LAST HDL_TAP TRUE
J 0
(-2675 2300);
DISPLAY 1.446809 (-2675 2300);
PAINT GREEN (-2675 2300);
DISPLAY INVISIBLE (-2675 2300);
FORCEPROP 1 LAST PATH I45
J 0
(-3002 2425);
DISPLAY 0.872340 (-3002 2425);
PAINT GREEN (-3002 2425);
DISPLAY INVISIBLE (-3002 2425);
FORCEADD TAP..1
(-3000 2375);
FORCEPROP 3 LASTPIN (-3050 2375) SIG_NAME P3E_CPU0_PE3_OCP_TXP<4>
J 0
(-3040 2385);
DISPLAY 0.659574 (-3040 2385);
PAINT MONO (-3040 2385);
DISPLAY INVISIBLE (-3040 2385);
FORCEPROP 1 LASTPIN (-3050 2375) BN 4
J 0
(-3062 2383);
DISPLAY 0.617021 (-3062 2383);
PAINT PINK (-3062 2383);
FORCEPROP 2 LAST CDS_LIB mstr_standard
J 2
(-3000 2375);
PAINT MONO (-3000 2375);
DISPLAY INVISIBLE (-3000 2375);
FORCEPROP 1 LAST BODY_TYPE PLUMBING
J 0
(-3000 2425);
DISPLAY 1.446809 (-3000 2425);
PAINT GREEN (-3000 2425);
DISPLAY INVISIBLE (-3000 2425);
FORCEPROP 1 LAST HDL_TAP TRUE
J 0
(-2675 2250);
DISPLAY 1.446809 (-2675 2250);
PAINT GREEN (-2675 2250);
DISPLAY INVISIBLE (-2675 2250);
FORCEPROP 1 LAST PATH I46
J 0
(-3002 2375);
DISPLAY 0.872340 (-3002 2375);
PAINT GREEN (-3002 2375);
DISPLAY INVISIBLE (-3002 2375);
FORCEADD TAP..1
(-3000 2025);
FORCEPROP 3 LASTPIN (-3050 2025) SIG_NAME P3E_CPU0_PE3_OCP_TXP<3>
J 0
(-3040 2035);
DISPLAY 0.659574 (-3040 2035);
PAINT MONO (-3040 2035);
DISPLAY INVISIBLE (-3040 2035);
FORCEPROP 1 LASTPIN (-3050 2025) BN 3
J 0
(-3062 2033);
DISPLAY 0.617021 (-3062 2033);
PAINT PINK (-3062 2033);
FORCEPROP 2 LAST CDS_LIB mstr_standard
J 2
(-3000 2025);
PAINT MONO (-3000 2025);
DISPLAY INVISIBLE (-3000 2025);
FORCEPROP 1 LAST BODY_TYPE PLUMBING
J 0
(-3000 2075);
DISPLAY 1.446809 (-3000 2075);
PAINT GREEN (-3000 2075);
DISPLAY INVISIBLE (-3000 2075);
FORCEPROP 1 LAST HDL_TAP TRUE
J 0
(-2675 1900);
DISPLAY 1.446809 (-2675 1900);
PAINT GREEN (-2675 1900);
DISPLAY INVISIBLE (-2675 1900);
FORCEPROP 1 LAST PATH I47
J 0
(-3002 2025);
DISPLAY 0.872340 (-3002 2025);
PAINT GREEN (-3002 2025);
DISPLAY INVISIBLE (-3002 2025);
FORCEADD TAP..1
(-2850 2125);
FORCEPROP 3 LASTPIN (-2900 2125) SIG_NAME P3E_CPU0_PE3_OCP_TXN<4>
J 0
(-2890 2135);
DISPLAY 0.659574 (-2890 2135);
PAINT MONO (-2890 2135);
DISPLAY INVISIBLE (-2890 2135);
FORCEPROP 1 LASTPIN (-2900 2125) BN 4
J 0
(-2912 2133);
DISPLAY 0.617021 (-2912 2133);
PAINT PINK (-2912 2133);
FORCEPROP 2 LAST CDS_LIB mstr_standard
J 2
(-2850 2125);
PAINT MONO (-2850 2125);
DISPLAY INVISIBLE (-2850 2125);
FORCEPROP 1 LAST BODY_TYPE PLUMBING
J 0
(-2850 2175);
DISPLAY 1.446809 (-2850 2175);
PAINT GREEN (-2850 2175);
DISPLAY INVISIBLE (-2850 2175);
FORCEPROP 1 LAST HDL_TAP TRUE
J 0
(-2525 2000);
DISPLAY 1.446809 (-2525 2000);
PAINT GREEN (-2525 2000);
DISPLAY INVISIBLE (-2525 2000);
FORCEPROP 1 LAST PATH I48
J 0
(-2852 2125);
DISPLAY 0.872340 (-2852 2125);
PAINT GREEN (-2852 2125);
DISPLAY INVISIBLE (-2852 2125);
FORCEADD TAP..1
(-2850 2175);
FORCEPROP 3 LASTPIN (-2900 2175) SIG_NAME P3E_CPU0_PE3_OCP_TXN<5>
J 0
(-2890 2185);
DISPLAY 0.659574 (-2890 2185);
PAINT MONO (-2890 2185);
DISPLAY INVISIBLE (-2890 2185);
FORCEPROP 1 LASTPIN (-2900 2175) BN 5
J 0
(-2912 2183);
DISPLAY 0.617021 (-2912 2183);
PAINT PINK (-2912 2183);
FORCEPROP 2 LAST CDS_LIB mstr_standard
J 2
(-2850 2175);
PAINT MONO (-2850 2175);
DISPLAY INVISIBLE (-2850 2175);
FORCEPROP 1 LAST BODY_TYPE PLUMBING
J 0
(-2850 2225);
DISPLAY 1.446809 (-2850 2225);
PAINT GREEN (-2850 2225);
DISPLAY INVISIBLE (-2850 2225);
FORCEPROP 1 LAST HDL_TAP TRUE
J 0
(-2525 2050);
DISPLAY 1.446809 (-2525 2050);
PAINT GREEN (-2525 2050);
DISPLAY INVISIBLE (-2525 2050);
FORCEPROP 1 LAST PATH I49
J 0
(-2852 2175);
DISPLAY 0.872340 (-2852 2175);
PAINT GREEN (-2852 2175);
DISPLAY INVISIBLE (-2852 2175);
FORCEADD TAP..1
R 2
(-6025 1725);
FORCEPROP 3 LASTPIN (-5975 1725) SIG_NAME P3E_CPU0_PE3_OCP_RXN<2>
J 0
(-5965 1735);
DISPLAY 0.659574 (-5965 1735);
PAINT MONO (-5965 1735);
DISPLAY INVISIBLE (-5965 1735);
FORCEPROP 1 LASTPIN (-5975 1725) BN 2
J 2
(-5963 1733);
DISPLAY 0.617021 (-5963 1733);
PAINT PINK (-5963 1733);
FORCEPROP 2 LAST CDS_LIB mstr_standard
J 0
(-6025 1725);
PAINT MONO (-6025 1725);
DISPLAY INVISIBLE (-6025 1725);
FORCEPROP 1 LAST BODY_TYPE PLUMBING
J 2
(-6025 1775);
DISPLAY 1.446809 (-6025 1775);
PAINT GREEN (-6025 1775);
DISPLAY INVISIBLE (-6025 1775);
FORCEPROP 1 LAST HDL_TAP TRUE
J 2
(-6350 1600);
DISPLAY 1.446809 (-6350 1600);
PAINT GREEN (-6350 1600);
DISPLAY INVISIBLE (-6350 1600);
FORCEPROP 1 LAST PATH I5
J 2
(-6023 1725);
DISPLAY 0.872340 (-6023 1725);
PAINT GREEN (-6023 1725);
DISPLAY INVISIBLE (-6023 1725);
FORCEADD TAP..1
(-2850 2225);
FORCEPROP 3 LASTPIN (-2900 2225) SIG_NAME P3E_CPU0_PE3_OCP_TXN<6>
J 0
(-2890 2235);
DISPLAY 0.659574 (-2890 2235);
PAINT MONO (-2890 2235);
DISPLAY INVISIBLE (-2890 2235);
FORCEPROP 1 LASTPIN (-2900 2225) BN 6
J 0
(-2912 2233);
DISPLAY 0.617021 (-2912 2233);
PAINT PINK (-2912 2233);
FORCEPROP 2 LAST CDS_LIB mstr_standard
J 2
(-2850 2225);
PAINT MONO (-2850 2225);
DISPLAY INVISIBLE (-2850 2225);
FORCEPROP 1 LAST BODY_TYPE PLUMBING
J 0
(-2850 2275);
DISPLAY 1.446809 (-2850 2275);
PAINT GREEN (-2850 2275);
DISPLAY INVISIBLE (-2850 2275);
FORCEPROP 1 LAST HDL_TAP TRUE
J 0
(-2525 2100);
DISPLAY 1.446809 (-2525 2100);
PAINT GREEN (-2525 2100);
DISPLAY INVISIBLE (-2525 2100);
FORCEPROP 1 LAST PATH I50
J 0
(-2852 2225);
DISPLAY 0.872340 (-2852 2225);
PAINT GREEN (-2852 2225);
DISPLAY INVISIBLE (-2852 2225);
FORCEADD TAP..1
(-2850 2275);
FORCEPROP 3 LASTPIN (-2900 2275) SIG_NAME P3E_CPU0_PE3_OCP_TXN<7>
J 0
(-2890 2285);
DISPLAY 0.659574 (-2890 2285);
PAINT MONO (-2890 2285);
DISPLAY INVISIBLE (-2890 2285);
FORCEPROP 1 LASTPIN (-2900 2275) BN 7
J 0
(-2912 2283);
DISPLAY 0.617021 (-2912 2283);
PAINT PINK (-2912 2283);
FORCEPROP 2 LAST CDS_LIB mstr_standard
J 2
(-2850 2275);
PAINT MONO (-2850 2275);
DISPLAY INVISIBLE (-2850 2275);
FORCEPROP 1 LAST BODY_TYPE PLUMBING
J 0
(-2850 2325);
DISPLAY 1.446809 (-2850 2325);
PAINT GREEN (-2850 2325);
DISPLAY INVISIBLE (-2850 2325);
FORCEPROP 1 LAST HDL_TAP TRUE
J 0
(-2525 2150);
DISPLAY 1.446809 (-2525 2150);
PAINT GREEN (-2525 2150);
DISPLAY INVISIBLE (-2525 2150);
FORCEPROP 1 LAST PATH I51
J 0
(-2852 2275);
DISPLAY 0.872340 (-2852 2275);
PAINT GREEN (-2852 2275);
DISPLAY INVISIBLE (-2852 2275);
FORCEADD TAP..1
(-3000 2975);
FORCEPROP 3 LASTPIN (-3050 2975) SIG_NAME P3E_CPU0_PE3_OCP_TXP<10>
J 0
(-3040 2985);
DISPLAY 0.659574 (-3040 2985);
PAINT MONO (-3040 2985);
DISPLAY INVISIBLE (-3040 2985);
FORCEPROP 1 LASTPIN (-3050 2975) BN 10
J 0
(-3062 2983);
DISPLAY 0.617021 (-3062 2983);
PAINT PINK (-3062 2983);
FORCEPROP 2 LAST CDS_LIB mstr_standard
J 2
(-3000 2975);
PAINT MONO (-3000 2975);
DISPLAY INVISIBLE (-3000 2975);
FORCEPROP 1 LAST BODY_TYPE PLUMBING
J 0
(-3000 3025);
DISPLAY 1.446809 (-3000 3025);
PAINT GREEN (-3000 3025);
DISPLAY INVISIBLE (-3000 3025);
FORCEPROP 1 LAST HDL_TAP TRUE
J 0
(-2675 2850);
DISPLAY 1.446809 (-2675 2850);
PAINT GREEN (-2675 2850);
DISPLAY INVISIBLE (-2675 2850);
FORCEPROP 1 LAST PATH I52
J 0
(-3002 2975);
DISPLAY 0.872340 (-3002 2975);
PAINT GREEN (-3002 2975);
DISPLAY INVISIBLE (-3002 2975);
FORCEADD TAP..1
(-3000 3025);
FORCEPROP 3 LASTPIN (-3050 3025) SIG_NAME P3E_CPU0_PE3_OCP_TXP<11>
J 0
(-3040 3035);
DISPLAY 0.659574 (-3040 3035);
PAINT MONO (-3040 3035);
DISPLAY INVISIBLE (-3040 3035);
FORCEPROP 1 LASTPIN (-3050 3025) BN 11
J 0
(-3062 3033);
DISPLAY 0.617021 (-3062 3033);
PAINT PINK (-3062 3033);
FORCEPROP 2 LAST CDS_LIB mstr_standard
J 2
(-3000 3025);
PAINT MONO (-3000 3025);
DISPLAY INVISIBLE (-3000 3025);
FORCEPROP 1 LAST BODY_TYPE PLUMBING
J 0
(-3000 3075);
DISPLAY 1.446809 (-3000 3075);
PAINT GREEN (-3000 3075);
DISPLAY INVISIBLE (-3000 3075);
FORCEPROP 1 LAST HDL_TAP TRUE
J 0
(-2675 2900);
DISPLAY 1.446809 (-2675 2900);
PAINT GREEN (-2675 2900);
DISPLAY INVISIBLE (-2675 2900);
FORCEPROP 1 LAST PATH I53
J 0
(-3002 3025);
DISPLAY 0.872340 (-3002 3025);
PAINT GREEN (-3002 3025);
DISPLAY INVISIBLE (-3002 3025);
FORCEADD TAP..1
(-3000 2925);
FORCEPROP 3 LASTPIN (-3050 2925) SIG_NAME P3E_CPU0_PE3_OCP_TXP<9>
J 0
(-3040 2935);
DISPLAY 0.659574 (-3040 2935);
PAINT MONO (-3040 2935);
DISPLAY INVISIBLE (-3040 2935);
FORCEPROP 1 LASTPIN (-3050 2925) BN 9
J 0
(-3062 2933);
DISPLAY 0.617021 (-3062 2933);
PAINT PINK (-3062 2933);
FORCEPROP 2 LAST CDS_LIB mstr_standard
J 2
(-3000 2925);
PAINT MONO (-3000 2925);
DISPLAY INVISIBLE (-3000 2925);
FORCEPROP 1 LAST BODY_TYPE PLUMBING
J 0
(-3000 2975);
DISPLAY 1.446809 (-3000 2975);
PAINT GREEN (-3000 2975);
DISPLAY INVISIBLE (-3000 2975);
FORCEPROP 1 LAST HDL_TAP TRUE
J 0
(-2675 2800);
DISPLAY 1.446809 (-2675 2800);
PAINT GREEN (-2675 2800);
DISPLAY INVISIBLE (-2675 2800);
FORCEPROP 1 LAST PATH I54
J 0
(-3002 2925);
DISPLAY 0.872340 (-3002 2925);
PAINT GREEN (-3002 2925);
DISPLAY INVISIBLE (-3002 2925);
FORCEADD TAP..1
(-3000 2875);
FORCEPROP 3 LASTPIN (-3050 2875) SIG_NAME P3E_CPU0_PE3_OCP_TXP<8>
J 0
(-3040 2885);
DISPLAY 0.659574 (-3040 2885);
PAINT MONO (-3040 2885);
DISPLAY INVISIBLE (-3040 2885);
FORCEPROP 1 LASTPIN (-3050 2875) BN 8
J 0
(-3062 2883);
DISPLAY 0.617021 (-3062 2883);
PAINT PINK (-3062 2883);
FORCEPROP 2 LAST CDS_LIB mstr_standard
J 2
(-3000 2875);
PAINT MONO (-3000 2875);
DISPLAY INVISIBLE (-3000 2875);
FORCEPROP 1 LAST BODY_TYPE PLUMBING
J 0
(-3000 2925);
DISPLAY 1.446809 (-3000 2925);
PAINT GREEN (-3000 2925);
DISPLAY INVISIBLE (-3000 2925);
FORCEPROP 1 LAST HDL_TAP TRUE
J 0
(-2675 2750);
DISPLAY 1.446809 (-2675 2750);
PAINT GREEN (-2675 2750);
DISPLAY INVISIBLE (-2675 2750);
FORCEPROP 1 LAST PATH I55
J 0
(-3002 2875);
DISPLAY 0.872340 (-3002 2875);
PAINT GREEN (-3002 2875);
DISPLAY INVISIBLE (-3002 2875);
FORCEADD TAP..1
(-2850 2625);
FORCEPROP 3 LASTPIN (-2900 2625) SIG_NAME P3E_CPU0_PE3_OCP_TXN<8>
J 0
(-2890 2635);
DISPLAY 0.659574 (-2890 2635);
PAINT MONO (-2890 2635);
DISPLAY INVISIBLE (-2890 2635);
FORCEPROP 1 LASTPIN (-2900 2625) BN 8
J 0
(-2912 2633);
DISPLAY 0.617021 (-2912 2633);
PAINT PINK (-2912 2633);
FORCEPROP 2 LAST CDS_LIB mstr_standard
J 2
(-2850 2625);
PAINT MONO (-2850 2625);
DISPLAY INVISIBLE (-2850 2625);
FORCEPROP 1 LAST BODY_TYPE PLUMBING
J 0
(-2850 2675);
DISPLAY 1.446809 (-2850 2675);
PAINT GREEN (-2850 2675);
DISPLAY INVISIBLE (-2850 2675);
FORCEPROP 1 LAST HDL_TAP TRUE
J 0
(-2525 2500);
DISPLAY 1.446809 (-2525 2500);
PAINT GREEN (-2525 2500);
DISPLAY INVISIBLE (-2525 2500);
FORCEPROP 1 LAST PATH I56
J 0
(-2852 2625);
DISPLAY 0.872340 (-2852 2625);
PAINT GREEN (-2852 2625);
DISPLAY INVISIBLE (-2852 2625);
FORCEADD TAP..1
(-2850 2725);
FORCEPROP 3 LASTPIN (-2900 2725) SIG_NAME P3E_CPU0_PE3_OCP_TXN<10>
J 0
(-2890 2735);
DISPLAY 0.659574 (-2890 2735);
PAINT MONO (-2890 2735);
DISPLAY INVISIBLE (-2890 2735);
FORCEPROP 1 LASTPIN (-2900 2725) BN 10
J 0
(-2912 2733);
DISPLAY 0.617021 (-2912 2733);
PAINT PINK (-2912 2733);
FORCEPROP 2 LAST CDS_LIB mstr_standard
J 2
(-2850 2725);
PAINT MONO (-2850 2725);
DISPLAY INVISIBLE (-2850 2725);
FORCEPROP 1 LAST BODY_TYPE PLUMBING
J 0
(-2850 2775);
DISPLAY 1.446809 (-2850 2775);
PAINT GREEN (-2850 2775);
DISPLAY INVISIBLE (-2850 2775);
FORCEPROP 1 LAST HDL_TAP TRUE
J 0
(-2525 2600);
DISPLAY 1.446809 (-2525 2600);
PAINT GREEN (-2525 2600);
DISPLAY INVISIBLE (-2525 2600);
FORCEPROP 1 LAST PATH I57
J 0
(-2852 2725);
DISPLAY 0.872340 (-2852 2725);
PAINT GREEN (-2852 2725);
DISPLAY INVISIBLE (-2852 2725);
FORCEADD TAP..1
(-2850 2675);
FORCEPROP 3 LASTPIN (-2900 2675) SIG_NAME P3E_CPU0_PE3_OCP_TXN<9>
J 0
(-2890 2685);
DISPLAY 0.659574 (-2890 2685);
PAINT MONO (-2890 2685);
DISPLAY INVISIBLE (-2890 2685);
FORCEPROP 1 LASTPIN (-2900 2675) BN 9
J 0
(-2912 2683);
DISPLAY 0.617021 (-2912 2683);
PAINT PINK (-2912 2683);
FORCEPROP 2 LAST CDS_LIB mstr_standard
J 2
(-2850 2675);
PAINT MONO (-2850 2675);
DISPLAY INVISIBLE (-2850 2675);
FORCEPROP 1 LAST BODY_TYPE PLUMBING
J 0
(-2850 2725);
DISPLAY 1.446809 (-2850 2725);
PAINT GREEN (-2850 2725);
DISPLAY INVISIBLE (-2850 2725);
FORCEPROP 1 LAST HDL_TAP TRUE
J 0
(-2525 2550);
DISPLAY 1.446809 (-2525 2550);
PAINT GREEN (-2525 2550);
DISPLAY INVISIBLE (-2525 2550);
FORCEPROP 1 LAST PATH I58
J 0
(-2852 2675);
DISPLAY 0.872340 (-2852 2675);
PAINT GREEN (-2852 2675);
DISPLAY INVISIBLE (-2852 2675);
FORCEADD TAP..1
(-2850 2775);
FORCEPROP 3 LASTPIN (-2900 2775) SIG_NAME P3E_CPU0_PE3_OCP_TXN<11>
J 0
(-2890 2785);
DISPLAY 0.659574 (-2890 2785);
PAINT MONO (-2890 2785);
DISPLAY INVISIBLE (-2890 2785);
FORCEPROP 1 LASTPIN (-2900 2775) BN 11
J 0
(-2912 2783);
DISPLAY 0.617021 (-2912 2783);
PAINT PINK (-2912 2783);
FORCEPROP 2 LAST CDS_LIB mstr_standard
J 2
(-2850 2775);
PAINT MONO (-2850 2775);
DISPLAY INVISIBLE (-2850 2775);
FORCEPROP 1 LAST BODY_TYPE PLUMBING
J 0
(-2850 2825);
DISPLAY 1.446809 (-2850 2825);
PAINT GREEN (-2850 2825);
DISPLAY INVISIBLE (-2850 2825);
FORCEPROP 1 LAST HDL_TAP TRUE
J 0
(-2525 2650);
DISPLAY 1.446809 (-2525 2650);
PAINT GREEN (-2525 2650);
DISPLAY INVISIBLE (-2525 2650);
FORCEPROP 1 LAST PATH I59
J 0
(-2852 2775);
DISPLAY 0.872340 (-2852 2775);
PAINT GREEN (-2852 2775);
DISPLAY INVISIBLE (-2852 2775);
FORCEADD TAP..1
R 2
(-6025 1775);
FORCEPROP 3 LASTPIN (-5975 1775) SIG_NAME P3E_CPU0_PE3_OCP_RXN<3>
J 0
(-5965 1785);
DISPLAY 0.659574 (-5965 1785);
PAINT MONO (-5965 1785);
DISPLAY INVISIBLE (-5965 1785);
FORCEPROP 1 LASTPIN (-5975 1775) BN 3
J 2
(-5963 1783);
DISPLAY 0.617021 (-5963 1783);
PAINT PINK (-5963 1783);
FORCEPROP 2 LAST CDS_LIB mstr_standard
J 0
(-6025 1775);
PAINT MONO (-6025 1775);
DISPLAY INVISIBLE (-6025 1775);
FORCEPROP 1 LAST BODY_TYPE PLUMBING
J 2
(-6025 1825);
DISPLAY 1.446809 (-6025 1825);
PAINT GREEN (-6025 1825);
DISPLAY INVISIBLE (-6025 1825);
FORCEPROP 1 LAST HDL_TAP TRUE
J 2
(-6350 1650);
DISPLAY 1.446809 (-6350 1650);
PAINT GREEN (-6350 1650);
DISPLAY INVISIBLE (-6350 1650);
FORCEPROP 1 LAST PATH I6
J 2
(-6023 1775);
DISPLAY 0.872340 (-6023 1775);
PAINT GREEN (-6023 1775);
DISPLAY INVISIBLE (-6023 1775);
FORCEADD TAP..1
(-3000 3425);
FORCEPROP 3 LASTPIN (-3050 3425) SIG_NAME P3E_CPU0_PE3_OCP_TXP<13>
J 0
(-3040 3435);
DISPLAY 0.659574 (-3040 3435);
PAINT MONO (-3040 3435);
DISPLAY INVISIBLE (-3040 3435);
FORCEPROP 1 LASTPIN (-3050 3425) BN 13
J 0
(-3062 3433);
DISPLAY 0.617021 (-3062 3433);
PAINT PINK (-3062 3433);
FORCEPROP 2 LAST CDS_LIB mstr_standard
J 2
(-3000 3425);
PAINT MONO (-3000 3425);
DISPLAY INVISIBLE (-3000 3425);
FORCEPROP 1 LAST BODY_TYPE PLUMBING
J 0
(-3000 3475);
DISPLAY 1.446809 (-3000 3475);
PAINT GREEN (-3000 3475);
DISPLAY INVISIBLE (-3000 3475);
FORCEPROP 1 LAST HDL_TAP TRUE
J 0
(-2675 3300);
DISPLAY 1.446809 (-2675 3300);
PAINT GREEN (-2675 3300);
DISPLAY INVISIBLE (-2675 3300);
FORCEPROP 1 LAST PATH I60
J 0
(-3002 3425);
DISPLAY 0.872340 (-3002 3425);
PAINT GREEN (-3002 3425);
DISPLAY INVISIBLE (-3002 3425);
FORCEADD TAP..1
(-3000 3525);
FORCEPROP 3 LASTPIN (-3050 3525) SIG_NAME P3E_CPU0_PE3_OCP_TXP<15>
J 0
(-3040 3535);
DISPLAY 0.659574 (-3040 3535);
PAINT MONO (-3040 3535);
DISPLAY INVISIBLE (-3040 3535);
FORCEPROP 1 LASTPIN (-3050 3525) BN 15
J 0
(-3062 3533);
DISPLAY 0.617021 (-3062 3533);
PAINT PINK (-3062 3533);
FORCEPROP 2 LAST CDS_LIB mstr_standard
J 2
(-3000 3525);
PAINT MONO (-3000 3525);
DISPLAY INVISIBLE (-3000 3525);
FORCEPROP 1 LAST BODY_TYPE PLUMBING
J 0
(-3000 3575);
DISPLAY 1.446809 (-3000 3575);
PAINT GREEN (-3000 3575);
DISPLAY INVISIBLE (-3000 3575);
FORCEPROP 1 LAST HDL_TAP TRUE
J 0
(-2675 3400);
DISPLAY 1.446809 (-2675 3400);
PAINT GREEN (-2675 3400);
DISPLAY INVISIBLE (-2675 3400);
FORCEPROP 1 LAST PATH I61
J 0
(-3002 3525);
DISPLAY 0.872340 (-3002 3525);
PAINT GREEN (-3002 3525);
DISPLAY INVISIBLE (-3002 3525);
FORCEADD TAP..1
(-3000 3375);
FORCEPROP 3 LASTPIN (-3050 3375) SIG_NAME P3E_CPU0_PE3_OCP_TXP<12>
J 0
(-3040 3385);
DISPLAY 0.659574 (-3040 3385);
PAINT MONO (-3040 3385);
DISPLAY INVISIBLE (-3040 3385);
FORCEPROP 1 LASTPIN (-3050 3375) BN 12
J 0
(-3062 3383);
DISPLAY 0.617021 (-3062 3383);
PAINT PINK (-3062 3383);
FORCEPROP 2 LAST CDS_LIB mstr_standard
J 2
(-3000 3375);
PAINT MONO (-3000 3375);
DISPLAY INVISIBLE (-3000 3375);
FORCEPROP 1 LAST BODY_TYPE PLUMBING
J 0
(-3000 3425);
DISPLAY 1.446809 (-3000 3425);
PAINT GREEN (-3000 3425);
DISPLAY INVISIBLE (-3000 3425);
FORCEPROP 1 LAST HDL_TAP TRUE
J 0
(-2675 3250);
DISPLAY 1.446809 (-2675 3250);
PAINT GREEN (-2675 3250);
DISPLAY INVISIBLE (-2675 3250);
FORCEPROP 1 LAST PATH I62
J 0
(-3002 3375);
DISPLAY 0.872340 (-3002 3375);
PAINT GREEN (-3002 3375);
DISPLAY INVISIBLE (-3002 3375);
FORCEADD TAP..1
(-3000 3475);
FORCEPROP 3 LASTPIN (-3050 3475) SIG_NAME P3E_CPU0_PE3_OCP_TXP<14>
J 0
(-3040 3485);
DISPLAY 0.659574 (-3040 3485);
PAINT MONO (-3040 3485);
DISPLAY INVISIBLE (-3040 3485);
FORCEPROP 1 LASTPIN (-3050 3475) BN 14
J 0
(-3062 3483);
DISPLAY 0.617021 (-3062 3483);
PAINT PINK (-3062 3483);
FORCEPROP 2 LAST CDS_LIB mstr_standard
J 2
(-3000 3475);
PAINT MONO (-3000 3475);
DISPLAY INVISIBLE (-3000 3475);
FORCEPROP 1 LAST BODY_TYPE PLUMBING
J 0
(-3000 3525);
DISPLAY 1.446809 (-3000 3525);
PAINT GREEN (-3000 3525);
DISPLAY INVISIBLE (-3000 3525);
FORCEPROP 1 LAST HDL_TAP TRUE
J 0
(-2675 3350);
DISPLAY 1.446809 (-2675 3350);
PAINT GREEN (-2675 3350);
DISPLAY INVISIBLE (-2675 3350);
FORCEPROP 1 LAST PATH I63
J 0
(-3002 3475);
DISPLAY 0.872340 (-3002 3475);
PAINT GREEN (-3002 3475);
DISPLAY INVISIBLE (-3002 3475);
FORCEADD TAP..1
(-2850 3125);
FORCEPROP 3 LASTPIN (-2900 3125) SIG_NAME P3E_CPU0_PE3_OCP_TXN<12>
J 0
(-2890 3135);
DISPLAY 0.659574 (-2890 3135);
PAINT MONO (-2890 3135);
DISPLAY INVISIBLE (-2890 3135);
FORCEPROP 1 LASTPIN (-2900 3125) BN 12
J 0
(-2912 3133);
DISPLAY 0.617021 (-2912 3133);
PAINT PINK (-2912 3133);
FORCEPROP 2 LAST CDS_LIB mstr_standard
J 2
(-2850 3125);
PAINT MONO (-2850 3125);
DISPLAY INVISIBLE (-2850 3125);
FORCEPROP 1 LAST BODY_TYPE PLUMBING
J 0
(-2850 3175);
DISPLAY 1.446809 (-2850 3175);
PAINT GREEN (-2850 3175);
DISPLAY INVISIBLE (-2850 3175);
FORCEPROP 1 LAST HDL_TAP TRUE
J 0
(-2525 3000);
DISPLAY 1.446809 (-2525 3000);
PAINT GREEN (-2525 3000);
DISPLAY INVISIBLE (-2525 3000);
FORCEPROP 1 LAST PATH I64
J 0
(-2852 3125);
DISPLAY 0.872340 (-2852 3125);
PAINT GREEN (-2852 3125);
DISPLAY INVISIBLE (-2852 3125);
FORCEADD TAP..1
(-2850 3175);
FORCEPROP 3 LASTPIN (-2900 3175) SIG_NAME P3E_CPU0_PE3_OCP_TXN<13>
J 0
(-2890 3185);
DISPLAY 0.659574 (-2890 3185);
PAINT MONO (-2890 3185);
DISPLAY INVISIBLE (-2890 3185);
FORCEPROP 1 LASTPIN (-2900 3175) BN 13
J 0
(-2912 3183);
DISPLAY 0.617021 (-2912 3183);
PAINT PINK (-2912 3183);
FORCEPROP 2 LAST CDS_LIB mstr_standard
J 2
(-2850 3175);
PAINT MONO (-2850 3175);
DISPLAY INVISIBLE (-2850 3175);
FORCEPROP 1 LAST BODY_TYPE PLUMBING
J 0
(-2850 3225);
DISPLAY 1.446809 (-2850 3225);
PAINT GREEN (-2850 3225);
DISPLAY INVISIBLE (-2850 3225);
FORCEPROP 1 LAST HDL_TAP TRUE
J 0
(-2525 3050);
DISPLAY 1.446809 (-2525 3050);
PAINT GREEN (-2525 3050);
DISPLAY INVISIBLE (-2525 3050);
FORCEPROP 1 LAST PATH I65
J 0
(-2852 3175);
DISPLAY 0.872340 (-2852 3175);
PAINT GREEN (-2852 3175);
DISPLAY INVISIBLE (-2852 3175);
FORCEADD TAP..1
(-2850 3275);
FORCEPROP 3 LASTPIN (-2900 3275) SIG_NAME P3E_CPU0_PE3_OCP_TXN<15>
J 0
(-2890 3285);
DISPLAY 0.659574 (-2890 3285);
PAINT MONO (-2890 3285);
DISPLAY INVISIBLE (-2890 3285);
FORCEPROP 1 LASTPIN (-2900 3275) BN 15
J 0
(-2912 3283);
DISPLAY 0.617021 (-2912 3283);
PAINT PINK (-2912 3283);
FORCEPROP 2 LAST CDS_LIB mstr_standard
J 2
(-2850 3275);
PAINT MONO (-2850 3275);
DISPLAY INVISIBLE (-2850 3275);
FORCEPROP 1 LAST BODY_TYPE PLUMBING
J 0
(-2850 3325);
DISPLAY 1.446809 (-2850 3325);
PAINT GREEN (-2850 3325);
DISPLAY INVISIBLE (-2850 3325);
FORCEPROP 1 LAST HDL_TAP TRUE
J 0
(-2525 3150);
DISPLAY 1.446809 (-2525 3150);
PAINT GREEN (-2525 3150);
DISPLAY INVISIBLE (-2525 3150);
FORCEPROP 1 LAST PATH I66
J 0
(-2852 3275);
DISPLAY 0.872340 (-2852 3275);
PAINT GREEN (-2852 3275);
DISPLAY INVISIBLE (-2852 3275);
FORCEADD TAP..1
(-2850 3225);
FORCEPROP 3 LASTPIN (-2900 3225) SIG_NAME P3E_CPU0_PE3_OCP_TXN<14>
J 0
(-2890 3235);
DISPLAY 0.659574 (-2890 3235);
PAINT MONO (-2890 3235);
DISPLAY INVISIBLE (-2890 3235);
FORCEPROP 1 LASTPIN (-2900 3225) BN 14
J 0
(-2912 3233);
DISPLAY 0.617021 (-2912 3233);
PAINT PINK (-2912 3233);
FORCEPROP 2 LAST CDS_LIB mstr_standard
J 2
(-2850 3225);
PAINT MONO (-2850 3225);
DISPLAY INVISIBLE (-2850 3225);
FORCEPROP 1 LAST BODY_TYPE PLUMBING
J 0
(-2850 3275);
DISPLAY 1.446809 (-2850 3275);
PAINT GREEN (-2850 3275);
DISPLAY INVISIBLE (-2850 3275);
FORCEPROP 1 LAST HDL_TAP TRUE
J 0
(-2525 3100);
DISPLAY 1.446809 (-2525 3100);
PAINT GREEN (-2525 3100);
DISPLAY INVISIBLE (-2525 3100);
FORCEPROP 1 LAST PATH I67
J 0
(-2852 3225);
DISPLAY 0.872340 (-2852 3225);
PAINT GREEN (-2852 3225);
DISPLAY INVISIBLE (-2852 3225);
FORCEADD OFFPAGE..2
(-1575 3500);
FORCEPROP 2 LAST $XR0 106 
J 0
(-1386 3500);
DISPLAY 0.638298 (-1386 3500);
PAINT MONO (-1386 3500);
FORCEPROP 2 LAST CDS_LIB mstr_standard
J 0
(-1575 3500);
PAINT MONO (-1575 3500);
DISPLAY INVISIBLE (-1575 3500);
FORCEPROP 1 LAST OFFPAGE TRUE
J 0
(-1250 3375);
DISPLAY 1.170213 (-1250 3375);
PAINT GREEN (-1250 3375);
DISPLAY INVISIBLE (-1250 3375);
FORCEPROP 1 LAST COMMENT_BODY TRUE
J 0
(-1620 3405);
DISPLAY 1.170213 (-1620 3405);
PAINT GREEN (-1620 3405);
DISPLAY INVISIBLE (-1620 3405);
FORCEPROP 2 LAST PATH I68
J 0
(-1400 3575);
DISPLAY 1.021277 (-1400 3575);
PAINT ORANGE (-1400 3575);
DISPLAY INVISIBLE (-1400 3575);
FORCEADD OFFPAGE..2
(-1575 3625);
FORCEPROP 2 LAST $XR0 106 
J 0
(-1386 3625);
DISPLAY 0.638298 (-1386 3625);
PAINT MONO (-1386 3625);
FORCEPROP 2 LAST CDS_LIB mstr_standard
J 0
(-1575 3625);
PAINT MONO (-1575 3625);
DISPLAY INVISIBLE (-1575 3625);
FORCEPROP 1 LAST OFFPAGE TRUE
J 0
(-1250 3500);
DISPLAY 1.170213 (-1250 3500);
PAINT GREEN (-1250 3500);
DISPLAY INVISIBLE (-1250 3500);
FORCEPROP 1 LAST COMMENT_BODY TRUE
J 0
(-1620 3530);
DISPLAY 1.170213 (-1620 3530);
PAINT GREEN (-1620 3530);
DISPLAY INVISIBLE (-1620 3530);
FORCEPROP 2 LAST PATH I69
J 0
(-1400 3700);
DISPLAY 1.021277 (-1400 3700);
PAINT ORANGE (-1400 3700);
DISPLAY INVISIBLE (-1400 3700);
FORCEADD TAP..1
R 2
(-5875 1875);
FORCEPROP 3 LASTPIN (-5825 1875) SIG_NAME P3E_CPU0_PE3_OCP_RXP<0>
J 0
(-5815 1885);
DISPLAY 0.659574 (-5815 1885);
PAINT MONO (-5815 1885);
DISPLAY INVISIBLE (-5815 1885);
FORCEPROP 1 LASTPIN (-5825 1875) BN 0
J 2
(-5813 1883);
DISPLAY 0.617021 (-5813 1883);
PAINT PINK (-5813 1883);
FORCEPROP 2 LAST CDS_LIB mstr_standard
J 0
(-5875 1875);
PAINT MONO (-5875 1875);
DISPLAY INVISIBLE (-5875 1875);
FORCEPROP 1 LAST BODY_TYPE PLUMBING
J 2
(-5875 1925);
DISPLAY 1.446809 (-5875 1925);
PAINT GREEN (-5875 1925);
DISPLAY INVISIBLE (-5875 1925);
FORCEPROP 1 LAST HDL_TAP TRUE
J 2
(-6200 1750);
DISPLAY 1.446809 (-6200 1750);
PAINT GREEN (-6200 1750);
DISPLAY INVISIBLE (-6200 1750);
FORCEPROP 1 LAST PATH I7
J 2
(-5873 1875);
DISPLAY 0.872340 (-5873 1875);
PAINT GREEN (-5873 1875);
DISPLAY INVISIBLE (-5873 1875);
FORCEADD TAP..1
R 2
(-5875 1925);
FORCEPROP 3 LASTPIN (-5825 1925) SIG_NAME P3E_CPU0_PE3_OCP_RXP<1>
J 0
(-5815 1935);
DISPLAY 0.659574 (-5815 1935);
PAINT MONO (-5815 1935);
DISPLAY INVISIBLE (-5815 1935);
FORCEPROP 1 LASTPIN (-5825 1925) BN 1
J 2
(-5813 1933);
DISPLAY 0.617021 (-5813 1933);
PAINT PINK (-5813 1933);
FORCEPROP 2 LAST CDS_LIB mstr_standard
J 0
(-5875 1925);
PAINT MONO (-5875 1925);
DISPLAY INVISIBLE (-5875 1925);
FORCEPROP 1 LAST BODY_TYPE PLUMBING
J 2
(-5875 1975);
DISPLAY 1.446809 (-5875 1975);
PAINT GREEN (-5875 1975);
DISPLAY INVISIBLE (-5875 1975);
FORCEPROP 1 LAST HDL_TAP TRUE
J 2
(-6200 1800);
DISPLAY 1.446809 (-6200 1800);
PAINT GREEN (-6200 1800);
DISPLAY INVISIBLE (-6200 1800);
FORCEPROP 1 LAST PATH I8
J 2
(-5873 1925);
DISPLAY 0.872340 (-5873 1925);
PAINT GREEN (-5873 1925);
DISPLAY INVISIBLE (-5873 1925);
FORCEADD TAP..6
(-5875 2525);
FORCEPROP 3 LASTPIN (-5825 2525) SIG_NAME P3E_CPU0_PE3_OCP_RXP<7>
J 0
(-5815 2535);
DISPLAY 0.659574 (-5815 2535);
PAINT MONO (-5815 2535);
DISPLAY INVISIBLE (-5815 2535);
FORCEPROP 1 LASTPIN (-5825 2525) BN 7
J 0
(-5877 2533);
DISPLAY 0.617021 (-5877 2533);
PAINT GREEN (-5877 2533);
FORCEPROP 2 LAST CDS_LIB mstr_standard
J 0
(-5875 2525);
PAINT MONO (-5875 2525);
DISPLAY INVISIBLE (-5875 2525);
FORCEPROP 1 LAST BODY_TYPE PLUMBING
J 0
(-5875 2475);
DISPLAY 0.872340 (-5875 2475);
PAINT GREEN (-5875 2475);
DISPLAY INVISIBLE (-5875 2475);
FORCEPROP 1 LAST HDL_TAP TRUE
J 0
(-5550 2400);
DISPLAY 0.872340 (-5550 2400);
PAINT ORANGE (-5550 2400);
DISPLAY INVISIBLE (-5550 2400);
FORCEPROP 1 LAST PATH I81
J 0
(-5877 2525);
DISPLAY 0.872340 (-5877 2525);
PAINT GREEN (-5877 2525);
DISPLAY INVISIBLE (-5877 2525);
FORCEADD TAP..6
(-5875 2475);
FORCEPROP 3 LASTPIN (-5825 2475) SIG_NAME P3E_CPU0_PE3_OCP_RXP<6>
J 0
(-5815 2485);
DISPLAY 0.659574 (-5815 2485);
PAINT MONO (-5815 2485);
DISPLAY INVISIBLE (-5815 2485);
FORCEPROP 1 LASTPIN (-5825 2475) BN 6
J 0
(-5877 2483);
DISPLAY 0.617021 (-5877 2483);
PAINT GREEN (-5877 2483);
FORCEPROP 2 LAST CDS_LIB mstr_standard
J 0
(-5875 2475);
PAINT MONO (-5875 2475);
DISPLAY INVISIBLE (-5875 2475);
FORCEPROP 1 LAST BODY_TYPE PLUMBING
J 0
(-5875 2425);
DISPLAY 0.872340 (-5875 2425);
PAINT GREEN (-5875 2425);
DISPLAY INVISIBLE (-5875 2425);
FORCEPROP 1 LAST HDL_TAP TRUE
J 0
(-5550 2350);
DISPLAY 0.872340 (-5550 2350);
PAINT ORANGE (-5550 2350);
DISPLAY INVISIBLE (-5550 2350);
FORCEPROP 1 LAST PATH I82
J 0
(-5877 2475);
DISPLAY 0.872340 (-5877 2475);
PAINT GREEN (-5877 2475);
DISPLAY INVISIBLE (-5877 2475);
FORCEADD TAP..6
(-5875 2425);
FORCEPROP 3 LASTPIN (-5825 2425) SIG_NAME P3E_CPU0_PE3_OCP_RXP<5>
J 0
(-5815 2435);
DISPLAY 0.659574 (-5815 2435);
PAINT MONO (-5815 2435);
DISPLAY INVISIBLE (-5815 2435);
FORCEPROP 1 LASTPIN (-5825 2425) BN 5
J 0
(-5877 2433);
DISPLAY 0.617021 (-5877 2433);
PAINT GREEN (-5877 2433);
FORCEPROP 2 LAST CDS_LIB mstr_standard
J 0
(-5875 2425);
PAINT MONO (-5875 2425);
DISPLAY INVISIBLE (-5875 2425);
FORCEPROP 1 LAST BODY_TYPE PLUMBING
J 0
(-5875 2375);
DISPLAY 0.872340 (-5875 2375);
PAINT GREEN (-5875 2375);
DISPLAY INVISIBLE (-5875 2375);
FORCEPROP 1 LAST HDL_TAP TRUE
J 0
(-5550 2300);
DISPLAY 0.872340 (-5550 2300);
PAINT ORANGE (-5550 2300);
DISPLAY INVISIBLE (-5550 2300);
FORCEPROP 1 LAST PATH I83
J 0
(-5877 2425);
DISPLAY 0.872340 (-5877 2425);
PAINT GREEN (-5877 2425);
DISPLAY INVISIBLE (-5877 2425);
FORCEADD TAP..6
(-5875 2375);
FORCEPROP 3 LASTPIN (-5825 2375) SIG_NAME P3E_CPU0_PE3_OCP_RXP<4>
J 0
(-5815 2385);
DISPLAY 0.659574 (-5815 2385);
PAINT MONO (-5815 2385);
DISPLAY INVISIBLE (-5815 2385);
FORCEPROP 1 LASTPIN (-5825 2375) BN 4
J 0
(-5877 2383);
DISPLAY 0.617021 (-5877 2383);
PAINT GREEN (-5877 2383);
FORCEPROP 2 LAST CDS_LIB mstr_standard
J 0
(-5875 2375);
PAINT MONO (-5875 2375);
DISPLAY INVISIBLE (-5875 2375);
FORCEPROP 1 LAST BODY_TYPE PLUMBING
J 0
(-5875 2325);
DISPLAY 0.872340 (-5875 2325);
PAINT GREEN (-5875 2325);
DISPLAY INVISIBLE (-5875 2325);
FORCEPROP 1 LAST HDL_TAP TRUE
J 0
(-5550 2250);
DISPLAY 0.872340 (-5550 2250);
PAINT ORANGE (-5550 2250);
DISPLAY INVISIBLE (-5550 2250);
FORCEPROP 1 LAST PATH I84
J 0
(-5877 2375);
DISPLAY 0.872340 (-5877 2375);
PAINT GREEN (-5877 2375);
DISPLAY INVISIBLE (-5877 2375);
FORCEADD TAP..6
(-6025 2275);
FORCEPROP 3 LASTPIN (-5975 2275) SIG_NAME P3E_CPU0_PE3_OCP_RXN<7>
J 0
(-5965 2285);
DISPLAY 0.659574 (-5965 2285);
PAINT MONO (-5965 2285);
DISPLAY INVISIBLE (-5965 2285);
FORCEPROP 1 LASTPIN (-5975 2275) BN 7
J 0
(-6027 2283);
DISPLAY 0.617021 (-6027 2283);
PAINT GREEN (-6027 2283);
FORCEPROP 2 LAST CDS_LIB mstr_standard
J 0
(-6025 2275);
PAINT MONO (-6025 2275);
DISPLAY INVISIBLE (-6025 2275);
FORCEPROP 1 LAST BODY_TYPE PLUMBING
J 0
(-6025 2225);
DISPLAY 0.872340 (-6025 2225);
PAINT GREEN (-6025 2225);
DISPLAY INVISIBLE (-6025 2225);
FORCEPROP 1 LAST HDL_TAP TRUE
J 0
(-5700 2150);
DISPLAY 0.872340 (-5700 2150);
PAINT ORANGE (-5700 2150);
DISPLAY INVISIBLE (-5700 2150);
FORCEPROP 1 LAST PATH I85
J 0
(-6027 2275);
DISPLAY 0.872340 (-6027 2275);
PAINT GREEN (-6027 2275);
DISPLAY INVISIBLE (-6027 2275);
FORCEADD TAP..6
(-6025 2225);
FORCEPROP 3 LASTPIN (-5975 2225) SIG_NAME P3E_CPU0_PE3_OCP_RXN<6>
J 0
(-5965 2235);
DISPLAY 0.659574 (-5965 2235);
PAINT MONO (-5965 2235);
DISPLAY INVISIBLE (-5965 2235);
FORCEPROP 1 LASTPIN (-5975 2225) BN 6
J 0
(-6027 2233);
DISPLAY 0.617021 (-6027 2233);
PAINT GREEN (-6027 2233);
FORCEPROP 2 LAST CDS_LIB mstr_standard
J 0
(-6025 2225);
PAINT MONO (-6025 2225);
DISPLAY INVISIBLE (-6025 2225);
FORCEPROP 1 LAST BODY_TYPE PLUMBING
J 0
(-6025 2175);
DISPLAY 0.872340 (-6025 2175);
PAINT GREEN (-6025 2175);
DISPLAY INVISIBLE (-6025 2175);
FORCEPROP 1 LAST HDL_TAP TRUE
J 0
(-5700 2100);
DISPLAY 0.872340 (-5700 2100);
PAINT ORANGE (-5700 2100);
DISPLAY INVISIBLE (-5700 2100);
FORCEPROP 1 LAST PATH I86
J 0
(-6027 2225);
DISPLAY 0.872340 (-6027 2225);
PAINT GREEN (-6027 2225);
DISPLAY INVISIBLE (-6027 2225);
FORCEADD TAP..6
(-6025 2175);
FORCEPROP 3 LASTPIN (-5975 2175) SIG_NAME P3E_CPU0_PE3_OCP_RXN<5>
J 0
(-5965 2185);
DISPLAY 0.659574 (-5965 2185);
PAINT MONO (-5965 2185);
DISPLAY INVISIBLE (-5965 2185);
FORCEPROP 1 LASTPIN (-5975 2175) BN 5
J 0
(-6027 2183);
DISPLAY 0.617021 (-6027 2183);
PAINT GREEN (-6027 2183);
FORCEPROP 2 LAST CDS_LIB mstr_standard
J 0
(-6025 2175);
PAINT MONO (-6025 2175);
DISPLAY INVISIBLE (-6025 2175);
FORCEPROP 1 LAST BODY_TYPE PLUMBING
J 0
(-6025 2125);
DISPLAY 0.872340 (-6025 2125);
PAINT GREEN (-6025 2125);
DISPLAY INVISIBLE (-6025 2125);
FORCEPROP 1 LAST HDL_TAP TRUE
J 0
(-5700 2050);
DISPLAY 0.872340 (-5700 2050);
PAINT ORANGE (-5700 2050);
DISPLAY INVISIBLE (-5700 2050);
FORCEPROP 1 LAST PATH I87
J 0
(-6027 2175);
DISPLAY 0.872340 (-6027 2175);
PAINT GREEN (-6027 2175);
DISPLAY INVISIBLE (-6027 2175);
FORCEADD TAP..6
(-6025 2125);
FORCEPROP 3 LASTPIN (-5975 2125) SIG_NAME P3E_CPU0_PE3_OCP_RXN<4>
J 0
(-5965 2135);
DISPLAY 0.659574 (-5965 2135);
PAINT MONO (-5965 2135);
DISPLAY INVISIBLE (-5965 2135);
FORCEPROP 1 LASTPIN (-5975 2125) BN 4
J 0
(-6027 2133);
DISPLAY 0.617021 (-6027 2133);
PAINT GREEN (-6027 2133);
FORCEPROP 2 LAST CDS_LIB mstr_standard
J 0
(-6025 2125);
PAINT MONO (-6025 2125);
DISPLAY INVISIBLE (-6025 2125);
FORCEPROP 1 LAST BODY_TYPE PLUMBING
J 0
(-6025 2075);
DISPLAY 0.872340 (-6025 2075);
PAINT GREEN (-6025 2075);
DISPLAY INVISIBLE (-6025 2075);
FORCEPROP 1 LAST HDL_TAP TRUE
J 0
(-5700 2000);
DISPLAY 0.872340 (-5700 2000);
PAINT ORANGE (-5700 2000);
DISPLAY INVISIBLE (-5700 2000);
FORCEPROP 1 LAST PATH I88
J 0
(-6027 2125);
DISPLAY 0.872340 (-6027 2125);
PAINT GREEN (-6027 2125);
DISPLAY INVISIBLE (-6027 2125);
FORCEADD SKX_EXT_B..12
(-4200 2575);
FORCEPROP 1 LAST LOCATION U5D1
J 0
(-4900 3775);
DISPLAY 0.617021 (-4900 3775);
PAINT AQUA (-4900 3775);
FORCEPROP 1 LAST PART_NUMBER TBD
J 0
(-4900 1425);
DISPLAY 0.617021 (-4900 1425);
PAINT BLUE (-4900 1425);
FORCEPROP 1 LAST MATERIAL IC
J 0
(-4900 3725);
DISPLAY 0.617021 (-4900 3725);
PAINT SKYBLUE (-4900 3725);
FORCEPROP 2 LASTPIN (-3450 3525) $PN CV5
J 0
(-3440 3535);
DISPLAY 0.617021 (-3440 3535);
PAINT ORANGE (-3440 3535);
FORCEPROP 2 LASTPIN (-3450 3475) $PN DA4
J 0
(-3440 3485);
DISPLAY 0.617021 (-3440 3485);
PAINT ORANGE (-3440 3485);
FORCEPROP 2 LASTPIN (-3450 3425) $PN DC6
J 0
(-3440 3435);
DISPLAY 0.617021 (-3440 3435);
PAINT ORANGE (-3440 3435);
FORCEPROP 2 LASTPIN (-3450 3375) $PN DG6
J 0
(-3440 3385);
DISPLAY 0.617021 (-3440 3385);
PAINT ORANGE (-3440 3385);
FORCEPROP 2 LASTPIN (-3450 3025) $PN DH5
J 0
(-3440 3035);
DISPLAY 0.617021 (-3440 3035);
PAINT ORANGE (-3440 3035);
FORCEPROP 2 LASTPIN (-3450 2975) $PN DK5
J 0
(-3440 2985);
DISPLAY 0.617021 (-3440 2985);
PAINT ORANGE (-3440 2985);
FORCEPROP 2 LASTPIN (-3450 2925) $PN DM5
J 0
(-3440 2935);
DISPLAY 0.617021 (-3440 2935);
PAINT ORANGE (-3440 2935);
FORCEPROP 2 LASTPIN (-3450 2875) $PN DN6
J 0
(-3440 2885);
DISPLAY 0.617021 (-3440 2885);
PAINT ORANGE (-3440 2885);
FORCEPROP 2 LASTPIN (-3450 2525) $PN DP7
J 0
(-3440 2535);
DISPLAY 0.617021 (-3440 2535);
PAINT ORANGE (-3440 2535);
FORCEPROP 2 LASTPIN (-3450 2475) $PN DT9
J 0
(-3440 2485);
DISPLAY 0.617021 (-3440 2485);
PAINT ORANGE (-3440 2485);
FORCEPROP 2 LASTPIN (-3450 2425) $PN DV9
J 0
(-3440 2435);
DISPLAY 0.617021 (-3440 2435);
PAINT ORANGE (-3440 2435);
FORCEPROP 2 LASTPIN (-3450 2375) $PN DY9
J 0
(-3440 2385);
DISPLAY 0.617021 (-3440 2385);
PAINT ORANGE (-3440 2385);
FORCEPROP 2 LASTPIN (-3450 2025) $PN EA10
J 0
(-3440 2035);
DISPLAY 0.617021 (-3440 2035);
PAINT ORANGE (-3440 2035);
FORCEPROP 2 LASTPIN (-3450 1975) $PN EB11
J 0
(-3440 1985);
DISPLAY 0.617021 (-3440 1985);
PAINT ORANGE (-3440 1985);
FORCEPROP 2 LASTPIN (-3450 1925) $PN ED13
J 0
(-3440 1935);
DISPLAY 0.617021 (-3440 1935);
PAINT ORANGE (-3440 1935);
FORCEPROP 2 LASTPIN (-3450 1875) $PN EC14
J 0
(-3440 1885);
DISPLAY 0.617021 (-3440 1885);
PAINT ORANGE (-3440 1885);
FORCEPROP 2 LASTPIN (-3450 3275) $PN CY5
J 0
(-3440 3285);
DISPLAY 0.617021 (-3440 3285);
PAINT ORANGE (-3440 3285);
FORCEPROP 2 LASTPIN (-3450 3225) $PN DB5
J 0
(-3440 3235);
DISPLAY 0.617021 (-3440 3235);
PAINT ORANGE (-3440 3235);
FORCEPROP 2 LASTPIN (-3450 3175) $PN DD5
J 0
(-3440 3185);
DISPLAY 0.617021 (-3440 3185);
PAINT ORANGE (-3440 3185);
FORCEPROP 2 LASTPIN (-3450 3125) $PN DJ6
J 0
(-3440 3135);
DISPLAY 0.617021 (-3440 3135);
PAINT ORANGE (-3440 3135);
FORCEPROP 2 LASTPIN (-3450 2775) $PN DJ4
J 0
(-3440 2785);
DISPLAY 0.617021 (-3440 2785);
PAINT ORANGE (-3440 2785);
FORCEPROP 2 LASTPIN (-3450 2725) $PN DL6
J 0
(-3440 2735);
DISPLAY 0.617021 (-3440 2735);
PAINT ORANGE (-3440 2735);
FORCEPROP 2 LASTPIN (-3450 2675) $PN DP5
J 0
(-3440 2685);
DISPLAY 0.617021 (-3440 2685);
PAINT ORANGE (-3440 2685);
FORCEPROP 2 LASTPIN (-3450 2625) $PN DM7
J 0
(-3440 2635);
DISPLAY 0.617021 (-3440 2635);
PAINT ORANGE (-3440 2635);
FORCEPROP 2 LASTPIN (-3450 2275) $PN DR8
J 0
(-3440 2285);
DISPLAY 0.617021 (-3440 2285);
PAINT ORANGE (-3440 2285);
FORCEPROP 2 LASTPIN (-3450 2225) $PN DU8
J 0
(-3440 2235);
DISPLAY 0.617021 (-3440 2235);
PAINT ORANGE (-3440 2235);
FORCEPROP 2 LASTPIN (-3450 2175) $PN DW10
J 0
(-3440 2185);
DISPLAY 0.617021 (-3440 2185);
PAINT ORANGE (-3440 2185);
FORCEPROP 2 LASTPIN (-3450 2125) $PN EB9
J 0
(-3440 2135);
DISPLAY 0.617021 (-3440 2135);
PAINT ORANGE (-3440 2135);
FORCEPROP 2 LASTPIN (-3450 1775) $PN DY11
J 0
(-3440 1785);
DISPLAY 0.617021 (-3440 1785);
PAINT ORANGE (-3440 1785);
FORCEPROP 2 LASTPIN (-3450 1725) $PN EC12
J 0
(-3440 1735);
DISPLAY 0.617021 (-3440 1735);
PAINT ORANGE (-3440 1735);
FORCEPROP 2 LASTPIN (-3450 1675) $PN EE12
J 0
(-3440 1685);
DISPLAY 0.617021 (-3440 1685);
PAINT ORANGE (-3440 1685);
FORCEPROP 2 LASTPIN (-3450 1625) $PN EE14
J 0
(-3440 1635);
DISPLAY 0.617021 (-3440 1635);
PAINT ORANGE (-3440 1635);
FORCEPROP 2 LASTPIN (-4950 3525) $PN CU10
J 2
(-4960 3535);
DISPLAY 0.617021 (-4960 3535);
PAINT ORANGE (-4960 3535);
FORCEPROP 2 LASTPIN (-4950 3475) $PN CW10
J 2
(-4960 3485);
DISPLAY 0.617021 (-4960 3485);
PAINT ORANGE (-4960 3485);
FORCEPROP 2 LASTPIN (-4950 3425) $PN DA12
J 2
(-4960 3435);
DISPLAY 0.617021 (-4960 3435);
PAINT ORANGE (-4960 3435);
FORCEPROP 2 LASTPIN (-4950 3375) $PN DC12
J 2
(-4960 3385);
DISPLAY 0.617021 (-4960 3385);
PAINT ORANGE (-4960 3385);
FORCEPROP 2 LASTPIN (-4950 3025) $PN DF11
J 2
(-4960 3035);
DISPLAY 0.617021 (-4960 3035);
PAINT ORANGE (-4960 3035);
FORCEPROP 2 LASTPIN (-4950 2975) $PN DE12
J 2
(-4960 2985);
DISPLAY 0.617021 (-4960 2985);
PAINT ORANGE (-4960 2985);
FORCEPROP 2 LASTPIN (-4950 2925) $PN DH11
J 2
(-4960 2935);
DISPLAY 0.617021 (-4960 2935);
PAINT ORANGE (-4960 2935);
FORCEPROP 2 LASTPIN (-4950 2875) $PN DK13
J 2
(-4960 2885);
DISPLAY 0.617021 (-4960 2885);
PAINT ORANGE (-4960 2885);
FORCEPROP 2 LASTPIN (-4950 2525) $PN DJ14
J 2
(-4960 2535);
DISPLAY 0.617021 (-4960 2535);
PAINT ORANGE (-4960 2535);
FORCEPROP 2 LASTPIN (-4950 2475) $PN DM13
J 2
(-4960 2485);
DISPLAY 0.617021 (-4960 2485);
PAINT ORANGE (-4960 2485);
FORCEPROP 2 LASTPIN (-4950 2425) $PN DP15
J 2
(-4960 2435);
DISPLAY 0.617021 (-4960 2435);
PAINT ORANGE (-4960 2435);
FORCEPROP 2 LASTPIN (-4950 2375) $PN DN16
J 2
(-4960 2385);
DISPLAY 0.617021 (-4960 2385);
PAINT ORANGE (-4960 2385);
FORCEPROP 2 LASTPIN (-4950 2025) $PN DR18
J 2
(-4960 2035);
DISPLAY 0.617021 (-4960 2035);
PAINT ORANGE (-4960 2035);
FORCEPROP 2 LASTPIN (-4950 1975) $PN DV17
J 2
(-4960 1985);
DISPLAY 0.617021 (-4960 1985);
PAINT ORANGE (-4960 1985);
FORCEPROP 2 LASTPIN (-4950 1925) $PN DU18
J 2
(-4960 1935);
DISPLAY 0.617021 (-4960 1935);
PAINT ORANGE (-4960 1935);
FORCEPROP 2 LASTPIN (-4950 1875) $PN DY17
J 2
(-4960 1885);
DISPLAY 0.617021 (-4960 1885);
PAINT ORANGE (-4960 1885);
FORCEPROP 2 LASTPIN (-4950 3275) $PN CV9
J 2
(-4960 3285);
DISPLAY 0.617021 (-4960 3285);
PAINT ORANGE (-4960 3285);
FORCEPROP 2 LASTPIN (-4950 3225) $PN CY11
J 2
(-4960 3235);
DISPLAY 0.617021 (-4960 3235);
PAINT ORANGE (-4960 3235);
FORCEPROP 2 LASTPIN (-4950 3175) $PN DB11
J 2
(-4960 3185);
DISPLAY 0.617021 (-4960 3185);
PAINT ORANGE (-4960 3185);
FORCEPROP 2 LASTPIN (-4950 3125) $PN DD13
J 2
(-4960 3135);
DISPLAY 0.617021 (-4960 3135);
PAINT ORANGE (-4960 3135);
FORCEPROP 2 LASTPIN (-4950 2775) $PN DG10
J 2
(-4960 2785);
DISPLAY 0.617021 (-4960 2785);
PAINT ORANGE (-4960 2785);
FORCEPROP 2 LASTPIN (-4950 2725) $PN DG12
J 2
(-4960 2735);
DISPLAY 0.617021 (-4960 2735);
PAINT ORANGE (-4960 2735);
FORCEPROP 2 LASTPIN (-4950 2675) $PN DJ12
J 2
(-4960 2685);
DISPLAY 0.617021 (-4960 2685);
PAINT ORANGE (-4960 2685);
FORCEPROP 2 LASTPIN (-4950 2625) $PN DL12
J 2
(-4960 2635);
DISPLAY 0.617021 (-4960 2635);
PAINT ORANGE (-4960 2635);
FORCEPROP 2 LASTPIN (-4950 2275) $PN DL14
J 2
(-4960 2285);
DISPLAY 0.617021 (-4960 2285);
PAINT ORANGE (-4960 2285);
FORCEPROP 2 LASTPIN (-4950 2225) $PN DN14
J 2
(-4960 2235);
DISPLAY 0.617021 (-4960 2235);
PAINT ORANGE (-4960 2235);
FORCEPROP 2 LASTPIN (-4950 2175) $PN DR14
J 2
(-4960 2185);
DISPLAY 0.617021 (-4960 2185);
PAINT ORANGE (-4960 2185);
FORCEPROP 2 LASTPIN (-4950 2125) $PN DR16
J 2
(-4960 2135);
DISPLAY 0.617021 (-4960 2135);
PAINT ORANGE (-4960 2135);
FORCEPROP 2 LASTPIN (-4950 1775) $PN DT19
J 2
(-4960 1785);
DISPLAY 0.617021 (-4960 1785);
PAINT ORANGE (-4960 1785);
FORCEPROP 2 LASTPIN (-4950 1725) $PN DW16
J 2
(-4960 1735);
DISPLAY 0.617021 (-4960 1735);
PAINT ORANGE (-4960 1735);
FORCEPROP 2 LASTPIN (-4950 1675) $PN DW18
J 2
(-4960 1685);
DISPLAY 0.617021 (-4960 1685);
PAINT ORANGE (-4960 1685);
FORCEPROP 2 LASTPIN (-4950 1625) $PN EA18
J 2
(-4960 1635);
DISPLAY 0.617021 (-4960 1635);
PAINT ORANGE (-4960 1635);
FORCEPROP 1 LAST PACK_TYPE BGA1
J 0
(-4900 3825);
PAINT SKYBLUE (-4900 3825);
DISPLAY INVISIBLE (-4900 3825);
FORCEPROP 2 LAST CDS_LIB chpset_lib
J 0
(-4200 2575);
PAINT ORANGE (-4200 2575);
DISPLAY INVISIBLE (-4200 2575);
FORCEPROP 2 LAST SEC_TYPE BGA1
J 0
(-4900 3825);
DISPLAY 1.021277 (-4900 3825);
PAINT ORANGE (-4900 3825);
DISPLAY INVISIBLE (-4900 3825);
FORCEPROP 2 LAST SEC 12
J 0
(-4900 3825);
DISPLAY 0.680851 (-4900 3825);
PAINT MONO (-4900 3825);
DISPLAY INVISIBLE (-4900 3825);
FORCEPROP 2 LAST CDS_LOCATION U5D1
J 0
(-4900 3775);
DISPLAY 0.617021 (-4900 3775);
PAINT AQUA (-4900 3775);
DISPLAY INVISIBLE (-4900 3775);
FORCEPROP 1 LAST PATH I89
J 0
(-4200 3725);
PAINT GREEN (-4200 3725);
DISPLAY INVISIBLE (-4200 3725);
FORCEADD TAP..1
R 2
(-5875 1975);
FORCEPROP 3 LASTPIN (-5825 1975) SIG_NAME P3E_CPU0_PE3_OCP_RXP<2>
J 0
(-5815 1985);
DISPLAY 0.659574 (-5815 1985);
PAINT MONO (-5815 1985);
DISPLAY INVISIBLE (-5815 1985);
FORCEPROP 1 LASTPIN (-5825 1975) BN 2
J 2
(-5813 1983);
DISPLAY 0.617021 (-5813 1983);
PAINT PINK (-5813 1983);
FORCEPROP 2 LAST CDS_LIB mstr_standard
J 0
(-5875 1975);
PAINT MONO (-5875 1975);
DISPLAY INVISIBLE (-5875 1975);
FORCEPROP 1 LAST BODY_TYPE PLUMBING
J 2
(-5875 2025);
DISPLAY 1.446809 (-5875 2025);
PAINT GREEN (-5875 2025);
DISPLAY INVISIBLE (-5875 2025);
FORCEPROP 1 LAST HDL_TAP TRUE
J 2
(-6200 1850);
DISPLAY 1.446809 (-6200 1850);
PAINT GREEN (-6200 1850);
DISPLAY INVISIBLE (-6200 1850);
FORCEPROP 1 LAST PATH I9
J 2
(-5873 1975);
DISPLAY 0.872340 (-5873 1975);
PAINT GREEN (-5873 1975);
DISPLAY INVISIBLE (-5873 1975);
FORCEADD PRELIM..10
(-4190 2565);
PAINT GRAY (-4190 2565);
FORCEPROP 2 LAST CDS_LIB mstr_misc
J 0
(-4190 2565);
PAINT ORANGE (-4190 2565);
DISPLAY INVISIBLE (-4190 2565);
FORCEPROP 1 LAST COMMENT_BODY TRUE
J 0
(-4190 2565);
PAINT ORANGE (-4190 2565);
DISPLAY INVISIBLE (-4190 2565);
FORCEADD DESIGN_NOTE..1
(-4700 1325);
FORCEPROP 0 LAST L1 CPU SYMBOLS 1-30 ARE PRELIMINARY AND SUBJECT TO CHANGE
J 0
(-4900 1200);
DISPLAY 1.021277 (-4900 1200);
PAINT ORANGE (-4900 1200);
FORCEPROP 2 LAST CDS_LIB mstr_symbols
J 0
(-4700 1325);
PAINT ORANGE (-4700 1325);
DISPLAY INVISIBLE (-4700 1325);
FORCEPROP 1 LAST COMMENT_BODY TRUE
J 0
(-4675 1425);
DISPLAY 0.978723 (-4675 1425);
PAINT ORANGE (-4675 1425);
DISPLAY INVISIBLE (-4675 1425);
FORCEADD INTEL_CORP_BPAGE..1
(0 0);
FORCEPROP 1 LAST CDS_CON_LAST_MODIFIED Tue Dec 01 11:51:21 2015
J 0
(-1425 325);
DISPLAY 1.340426 (-1425 325);
PAINT GREEN (-1425 325);
DISPLAY INVISIBLE (-1425 325);
FORCEPROP 1 LAST CUSTOM_TXT_CDS <CURRENT_DESIGN_SHEET> OF <TOTAL_DESIGN_SHEETS>
J 0
(-500 25);
PAINT GREEN (-500 25);
FORCEPROP 1 LAST CUSTOM_TXT_CDS <CON_LAST_MODIFIED>
J 0
(-1925 350);
PAINT GREEN (-1925 350);
FORCEPROP 2 LAST CUSTOM_TXT_CDS <XR_PAGE_TITLE>
J 0
(-7890 5250);
DISPLAY 0.638298 (-7890 5250);
PAINT PINK (-7890 5250);
DISPLAY INVISIBLE (-7890 5250);
FORCEPROP 1 LAST SCH_ADDRESS3 Santa Clara, CA 95052-8119
J 0
(-3975 25);
DISPLAY 0.617021 (-3975 25);
PAINT GREEN (-3975 25);
FORCEPROP 1 LAST SCH_ADDRESS2 P.O. BOX 58119
J 0
(-3975 75);
DISPLAY 0.617021 (-3975 75);
PAINT GREEN (-3975 75);
FORCEPROP 1 LAST SCH_ADDRESS1 2200 Mission College Blvd.
J 0
(-3975 125);
DISPLAY 0.617021 (-3975 125);
PAINT GREEN (-3975 125);
FORCEPROP 1 LAST SCH_TITLE SKYLAKE - SKT0 - 12 OF 21
J 0
(-7950 50);
DISPLAY 1.212766 (-7950 50);
PAINT GREEN (-7950 50);
FORCEPROP 1 LAST SCH_NUMBER H4694802
J 0
(-1300 150);
DISPLAY 1.212766 (-1300 150);
PAINT YELLOW (-1300 150);
FORCEPROP 1 LAST SCH_DEPT BESD
J 1
(-4450 100);
DISPLAY 1.212766 (-4450 100);
PAINT YELLOW (-4450 100);
FORCEPROP 1 LAST SCH_REV 2.420
J 0
(-250 150);
DISPLAY 0.978723 (-250 150);
PAINT YELLOW (-250 150);
FORCEPROP 2 LAST PAGE_BORDER TRUE
J 0
(-7890 5250);
DISPLAY 0.851064 (-7890 5250);
PAINT PINK (-7890 5250);
DISPLAY INVISIBLE (-7890 5250);
FORCEPROP 2 LAST CDS_LIB mstr_symbols
J 0
(0 0);
PAINT ORANGE (0 0);
DISPLAY INVISIBLE (0 0);
FORCEPROP 1 LAST COMMENT_BODY TRUE
J 0
(12 12);
DISPLAY 0.638298 (12 12);
PAINT GREEN (12 12);
DISPLAY INVISIBLE (12 12);
FORCEPROP 2 LAST CDS_XR_PAGE_TITLE CR-32 : @BASEBOARD_FAB2_LIB.BASEBOARD_FAB2(SCH_1):PAGE32
J 0
(-7890 5250);
DISPLAY 0.638298 (-7890 5250);
PAINT PINK (-7890 5250);
DISPLAY INVISIBLE (-7890 5250);
WIRE 17 -1 (-2800 3250)(-2800 3300);
WIRE 17 -1 (-2800 3200)(-2800 3250);
WIRE 17 -1 (-2800 3300)(-2800 3500);
WIRE 17 -1 (-2800 3500)(-1625 3500);
FORCEPROP 2 LAST SIG_NAME P3E_CPU0_PE3_OCP_TXN<15:0>
J 0
(-2760 3510);
DISPLAY 0.617021 (-2760 3510);
PAINT ORANGE (-2760 3510);
WIRE 17 -1 (-2800 3150)(-2800 3200);
WIRE 17 -1 (-2800 2800)(-2800 3150);
WIRE 17 -1 (-2800 2750)(-2800 2800);
WIRE 17 -1 (-2800 2700)(-2800 2750);
WIRE 17 -1 (-2800 2700)(-2800 2650);
WIRE 17 -1 (-2800 2650)(-2800 2300);
WIRE 17 -1 (-2800 2250)(-2800 2300);
WIRE 17 -1 (-2800 2200)(-2800 2250);
WIRE 17 -1 (-2800 2150)(-2800 2200);
WIRE 17 -1 (-2800 1800)(-2800 2150);
WIRE 17 -1 (-2800 1750)(-2800 1800);
WIRE 17 -1 (-2800 1700)(-2800 1750);
WIRE 17 -1 (-2800 1650)(-2800 1700);
WIRE 17 -1 (-2950 3500)(-2950 3550);
WIRE 17 -1 (-2950 3450)(-2950 3500);
WIRE 17 -1 (-2950 3550)(-2950 3625);
WIRE 17 -1 (-2950 3625)(-1625 3625);
FORCEPROP 2 LAST SIG_NAME P3E_CPU0_PE3_OCP_TXP<15:0>
J 0
(-2760 3635);
DISPLAY 0.617021 (-2760 3635);
PAINT ORANGE (-2760 3635);
WIRE 17 -1 (-2950 3450)(-2950 3400);
WIRE 17 -1 (-2950 3050)(-2950 3400);
WIRE 17 -1 (-2950 3000)(-2950 3050);
WIRE 17 -1 (-2950 2950)(-2950 3000);
WIRE 17 -1 (-2950 2950)(-2950 2900);
WIRE 17 -1 (-2950 2550)(-2950 2900);
WIRE 17 -1 (-2950 2500)(-2950 2550);
WIRE 17 -1 (-2950 2450)(-2950 2500);
WIRE 17 -1 (-2950 2400)(-2950 2450);
WIRE 17 -1 (-2950 2050)(-2950 2400);
WIRE 17 -1 (-2950 2000)(-2950 2050);
WIRE 17 -1 (-2950 1950)(-2950 2000);
WIRE 17 -1 (-2950 1900)(-2950 1950);
WIRE 17 -1 (-6075 3500)(-6075 3300);
WIRE 17 -1 (-7225 3500)(-6075 3500);
FORCEPROP 2 LAST SIG_NAME P3E_CPU0_PE3_OCP_RXN<15:0>
J 0
(-7185 3510);
DISPLAY 0.617021 (-7185 3510);
PAINT ORANGE (-7185 3510);
WIRE 17 -1 (-6075 3300)(-6075 3250);
WIRE 17 -1 (-6075 3250)(-6075 3200);
WIRE 17 -1 (-6075 3200)(-6075 3150);
WIRE 17 -1 (-6075 2800)(-6075 3150);
WIRE 17 -1 (-6075 2800)(-6075 2750);
WIRE 17 -1 (-6075 2750)(-6075 2700);
WIRE 17 -1 (-6075 2700)(-6075 2650);
WIRE 17 -1 (-6075 2650)(-6075 2300);
WIRE 17 -1 (-6075 2300)(-6075 2250);
WIRE 17 -1 (-6075 2250)(-6075 2200);
WIRE 17 -1 (-6075 2200)(-6075 2150);
WIRE 16 -1 (-6075 1800)(-6075 2150);
WIRE 17 -1 (-6075 1800)(-6075 1750);
WIRE 17 -1 (-6075 1750)(-6075 1700);
WIRE 17 -1 (-6075 1700)(-6075 1650);
WIRE 17 -1 (-5925 3625)(-5925 3550);
WIRE 17 -1 (-7225 3625)(-5925 3625);
FORCEPROP 2 LAST SIG_NAME P3E_CPU0_PE3_OCP_RXP<15:0>
J 0
(-7185 3635);
DISPLAY 0.617021 (-7185 3635);
PAINT ORANGE (-7185 3635);
WIRE 17 -1 (-5925 3550)(-5925 3500);
WIRE 17 -1 (-5925 3500)(-5925 3450);
WIRE 17 -1 (-5925 3450)(-5925 3400);
WIRE 17 -1 (-5925 3400)(-5925 3050);
WIRE 17 -1 (-5925 3050)(-5925 3000);
WIRE 17 -1 (-5925 2950)(-5925 3000);
WIRE 17 -1 (-5925 2950)(-5925 2900);
WIRE 17 -1 (-5925 2900)(-5925 2550);
WIRE 17 -1 (-5925 2550)(-5925 2500);
WIRE 17 -1 (-5925 2500)(-5925 2450);
WIRE 17 -1 (-5925 2450)(-5925 2400);
WIRE 17 -1 (-5925 2400)(-5925 2050);
WIRE 17 -1 (-5925 2050)(-5925 2000);
WIRE 17 -1 (-5925 2000)(-5925 1950);
WIRE 17 -1 (-5925 1950)(-5925 1900);
WIRE 16 -1 (-5975 1775)(-4950 1775);
WIRE 16 -1 (-5825 1875)(-4950 1875);
WIRE 16 -1 (-5825 1925)(-4950 1925);
WIRE 16 -1 (-5825 1975)(-4950 1975);
WIRE 16 -1 (-5825 2025)(-4950 2025);
WIRE 16 -1 (-5975 1625)(-4950 1625);
WIRE 16 -1 (-5975 1675)(-4950 1675);
WIRE 16 -1 (-5975 1725)(-4950 1725);
WIRE 16 -1 (-5825 2375)(-4950 2375);
WIRE 16 -1 (-5825 2425)(-4950 2425);
WIRE 16 -1 (-5825 2475)(-4950 2475);
WIRE 16 -1 (-5825 2525)(-4950 2525);
WIRE 16 -1 (-5825 2875)(-4950 2875);
WIRE 16 -1 (-5825 2925)(-4950 2925);
WIRE 16 -1 (-5825 2975)(-4950 2975);
WIRE 16 -1 (-5825 3025)(-4950 3025);
WIRE 16 -1 (-5825 3375)(-4950 3375);
WIRE 16 -1 (-5825 3425)(-4950 3425);
WIRE 16 -1 (-5825 3475)(-4950 3475);
WIRE 16 -1 (-5825 3525)(-4950 3525);
WIRE 16 -1 (-5975 2125)(-4950 2125);
WIRE 16 -1 (-5975 2175)(-4950 2175);
WIRE 16 -1 (-5975 2225)(-4950 2225);
WIRE 16 -1 (-5975 2275)(-4950 2275);
WIRE 16 -1 (-5975 2625)(-4950 2625);
WIRE 16 -1 (-5975 2675)(-4950 2675);
WIRE 16 -1 (-5975 2725)(-4950 2725);
WIRE 16 -1 (-5975 2775)(-4950 2775);
WIRE 16 -1 (-5975 3125)(-4950 3125);
WIRE 16 -1 (-5975 3175)(-4950 3175);
WIRE 16 -1 (-5975 3225)(-4950 3225);
WIRE 16 -1 (-5975 3275)(-4950 3275);
WIRE 16 -1 (-3050 1875)(-3450 1875);
WIRE 16 -1 (-3050 1925)(-3450 1925);
WIRE 16 -1 (-3050 1975)(-3450 1975);
WIRE 16 -1 (-3050 2025)(-3450 2025);
WIRE 16 -1 (-2900 1625)(-3450 1625);
WIRE 16 -1 (-2900 1675)(-3450 1675);
WIRE 16 -1 (-2900 1725)(-3450 1725);
WIRE 16 -1 (-2900 1775)(-3450 1775);
WIRE 16 -1 (-3050 2375)(-3450 2375);
WIRE 16 -1 (-3050 2425)(-3450 2425);
WIRE 16 -1 (-3050 2475)(-3450 2475);
WIRE 16 -1 (-3050 2525)(-3450 2525);
WIRE 16 -1 (-3050 2875)(-3450 2875);
WIRE 16 -1 (-3050 2925)(-3450 2925);
WIRE 16 -1 (-3050 2975)(-3450 2975);
WIRE 16 -1 (-3050 3025)(-3450 3025);
WIRE 16 -1 (-3050 3375)(-3450 3375);
WIRE 16 -1 (-3050 3425)(-3450 3425);
WIRE 16 -1 (-3050 3475)(-3450 3475);
WIRE 16 -1 (-3050 3525)(-3450 3525);
WIRE 16 -1 (-2900 2125)(-3450 2125);
WIRE 16 -1 (-2900 2175)(-3450 2175);
WIRE 16 -1 (-2900 2225)(-3450 2225);
WIRE 16 -1 (-2900 2275)(-3450 2275);
WIRE 16 -1 (-2900 2625)(-3450 2625);
WIRE 16 -1 (-2900 2675)(-3450 2675);
WIRE 16 -1 (-2900 2725)(-3450 2725);
WIRE 16 -1 (-2900 2775)(-3450 2775);
WIRE 16 -1 (-2900 3125)(-3450 3125);
WIRE 16 -1 (-2900 3175)(-3450 3175);
WIRE 16 -1 (-2900 3225)(-3450 3225);
WIRE 16 -1 (-2900 3275)(-3450 3275);
FORCENOTE
BOM_COST=PROC_SOCKET
(-7950 250) 0;
DISPLAY LEFT (-7950 250);
DISPLAY 1.723404 (-7950 250);
PAINT PURPLE (-7950 250);
FORCENOTE
ROOM=CPU0
(-7950 375) 0;
DISPLAY LEFT (-7950 375);
DISPLAY 1.723404 (-7950 375);
PAINT PURPLE (-7950 375);
FORCENOTE
FROM OCP
(-7350 3325) 0;
DISPLAY LEFT (-7350 3325);
DISPLAY 1.021277 (-7350 3325);
PAINT PURPLE (-7350 3325);
FORCENOTE
TO OCP
(-2025 3300) 0;
DISPLAY LEFT (-2025 3300);
DISPLAY 1.021277 (-2025 3300);
PAINT PURPLE (-2025 3300);
QUIT
